FILE_TYPE = MACRO_DRAWING;
SET COLOR_WIRE YELLOW;
SET COLOR_PROP MONO;
SET COLOR_DOT WHITE;
SET COLOR_ARC YELLOW;
SET COLOR_BODY GREEN;
SET COLOR_NOTE MONO;
SET PROP_DISPLAY VALUE;
SET PAGE_NUMBER P175;
FORCEADD OFFPAGE..2
(-2275 2450);
FORCEPROP 2 LAST $XR0 118 
J 0
(-2086 2450);
DISPLAY 0.638298 (-2086 2450);
PAINT MONO (-2086 2450);
FORCEPROP 2 LAST CDS_LIB mstr_standard
J 0
(-2275 2450);
PAINT MONO (-2275 2450);
DISPLAY INVISIBLE (-2275 2450);
FORCEPROP 2 LAST PATH I100
J 0
(-2100 2525);
DISPLAY 1.021277 (-2100 2525);
PAINT ORANGE (-2100 2525);
DISPLAY INVISIBLE (-2100 2525);
FORCEPROP 1 LAST OFFPAGE TRUE
J 0
(-1950 2325);
DISPLAY 0.872340 (-1950 2325);
PAINT GREEN (-1950 2325);
DISPLAY INVISIBLE (-1950 2325);
FORCEPROP 1 LAST COMMENT_BODY TRUE
J 0
(-2320 2355);
DISPLAY 0.872340 (-2320 2355);
PAINT GREEN (-2320 2355);
DISPLAY INVISIBLE (-2320 2355);
FORCEADD CAP_A..1
(-4975 3950);
FORCEPROP 1 LAST PART_NUMBER D97712-004
J 0
(-4925 3800);
DISPLAY 0.617021 (-4925 3800);
PAINT BLUE (-4925 3800);
FORCEPROP 1 LAST VOLTAGE 6.3V
J 0
(-4925 3950);
DISPLAY 0.617021 (-4925 3950);
PAINT SKYBLUE (-4925 3950);
FORCEPROP 1 LAST VALUE 1.0UF
J 0
(-4925 4000);
DISPLAY 0.617021 (-4925 4000);
PAINT SKYBLUE (-4925 4000);
FORCEPROP 1 LAST PACK_TYPE 0402V
J 0
(-4925 3750);
DISPLAY 0.617021 (-4925 3750);
PAINT SKYBLUE (-4925 3750);
FORCEPROP 1 LAST MATERIAL X6S
J 0
(-4925 3850);
DISPLAY 0.617021 (-4925 3850);
PAINT SKYBLUE (-4925 3850);
FORCEPROP 1 LASTPIN (-4975 4050) $PN 1
J 0
(-4965 4030);
DISPLAY 0.617021 (-4965 4030);
PAINT ORANGE (-4965 4030);
FORCEPROP 1 LASTPIN (-4975 3850) $PN 2
J 0
(-4965 3830);
DISPLAY 0.617021 (-4965 3830);
PAINT ORANGE (-4965 3830);
FORCEPROP 1 LAST LOCATION C1L18
J 0
(-4925 4050);
DISPLAY 0.617021 (-4925 4050);
PAINT AQUA (-4925 4050);
FORCEPROP 1 LAST TOLERANCE 10%
J 0
(-4925 3900);
DISPLAY 0.617021 (-4925 3900);
PAINT SKYBLUE (-4925 3900);
FORCEPROP 2 LAST BOM_COST MIO_CHASSIS
J 0
(-4925 4150);
DISPLAY 1.021277 (-4925 4150);
PAINT ORANGE (-4925 4150);
DISPLAY INVISIBLE (-4925 4150);
FORCEPROP 2 LAST CDS_SEC 1
J 0
(-4925 4100);
PAINT ORANGE (-4925 4100);
DISPLAY INVISIBLE (-4925 4100);
FORCEPROP 2 LAST SEC_TYPE 0402V
J 0
(-4925 4150);
DISPLAY 1.021277 (-4925 4150);
PAINT ORANGE (-4925 4150);
DISPLAY INVISIBLE (-4925 4150);
FORCEPROP 2 LAST SEC 1
J 0
(-4925 4100);
DISPLAY 0.680851 (-4925 4100);
PAINT MONO (-4925 4100);
DISPLAY INVISIBLE (-4925 4100);
FORCEPROP 1 LAST PATH I11
J 0
(-4925 4100);
DISPLAY 0.978723 (-4925 4100);
PAINT WHITE (-4925 4100);
DISPLAY INVISIBLE (-4925 4100);
FORCEPROP 2 LAST ROOM MIO_CHASSIS
J 0
(-4925 4100);
DISPLAY 1.021277 (-4925 4100);
PAINT ORANGE (-4925 4100);
DISPLAY INVISIBLE (-4925 4100);
FORCEPROP 2 LAST CDS_LOCATION C1L18
J 0
(-4925 4050);
DISPLAY 0.617021 (-4925 4050);
PAINT AQUA (-4925 4050);
DISPLAY INVISIBLE (-4925 4050);
FORCEPROP 2 LAST CDS_LIB dev_discrete
J 0
(-4975 3950);
PAINT ORANGE (-4975 3950);
DISPLAY INVISIBLE (-4975 3950);
FORCEADD GND..1
(-4975 3675);
FORCEPROP 3 LASTPIN (-4975 3725) SIG_NAME GND\g
J 0
(-4965 3735);
DISPLAY 0.659574 (-4965 3735);
PAINT MONO (-4965 3735);
DISPLAY INVISIBLE (-4965 3735);
FORCEPROP 1 LAST VOLTAGE 0.0V
J 0
(-5020 3632);
DISPLAY 0.340426 (-5020 3632);
PAINT SKYBLUE (-5020 3632);
DISPLAY INVISIBLE (-5020 3632);
FORCEPROP 2 LAST CDS_LIB mstr_symbols
J 0
(-4975 3675);
PAINT ORANGE (-4975 3675);
DISPLAY INVISIBLE (-4975 3675);
FORCEPROP 1 LAST SIZE 1B
J 0
(-4900 3625);
DISPLAY 0.872340 (-4900 3625);
PAINT AQUA (-4900 3625);
DISPLAY INVISIBLE (-4900 3625);
FORCEPROP 1 LAST PATH I12
J 0
(-4900 3675);
DISPLAY 0.872340 (-4900 3675);
PAINT AQUA (-4900 3675);
DISPLAY INVISIBLE (-4900 3675);
FORCEPROP 1 LAST BODY_TYPE PLUMBING
J 0
(-5020 3632);
DISPLAY 0.340426 (-5020 3632);
PAINT GREEN (-5020 3632);
DISPLAY INVISIBLE (-5020 3632);
FORCEPROP 1 LAST HDL_POWER GND
J 0
(-4975 3825);
DISPLAY 0.872340 (-4975 3825);
PAINT GREEN (-4975 3825);
DISPLAY INVISIBLE (-4975 3825);
FORCEADD RES..1
(-2275 4075);
FORCEPROP 1 LAST PACK_TYPE 0402
J 0
(-2125 3975);
DISPLAY 0.617021 (-2125 3975);
PAINT SKYBLUE (-2125 3975);
FORCEPROP 1 LAST MATERIAL CHIP
J 0
(-2275 3925);
DISPLAY 0.617021 (-2275 3925);
PAINT SKYBLUE (-2275 3925);
FORCEPROP 1 LAST WATTAGE 1/16W
J 2
(-2300 3925);
DISPLAY 0.617021 (-2300 3925);
PAINT SKYBLUE (-2300 3925);
FORCEPROP 1 LAST VALUE 33.2
J 2
(-2300 3975);
DISPLAY 0.617021 (-2300 3975);
PAINT SKYBLUE (-2300 3975);
FORCEPROP 1 LASTPIN (-2375 4075) $PN 1
J 0
(-2363 4087);
DISPLAY 0.617021 (-2363 4087);
PAINT ORANGE (-2363 4087);
FORCEPROP 1 LAST TOLERANCE 1%
J 0
(-2275 3975);
DISPLAY 0.617021 (-2275 3975);
PAINT SKYBLUE (-2275 3975);
FORCEPROP 1 LAST LOCATION R1L26
J 0
(-2325 4125);
DISPLAY 0.617021 (-2325 4125);
PAINT AQUA (-2325 4125);
FORCEPROP 1 LASTPIN (-2175 4075) $PN 2
J 0
(-2213 4087);
DISPLAY 0.617021 (-2213 4087);
PAINT ORANGE (-2213 4087);
FORCEPROP 1 LAST PART_NUMBER G21796-074
J 0
(-2325 4175);
DISPLAY 0.617021 (-2325 4175);
PAINT BLUE (-2325 4175);
FORCEPROP 2 LAST SEC_TYPE 0402
J 0
(-2325 4275);
DISPLAY 1.021277 (-2325 4275);
PAINT ORANGE (-2325 4275);
DISPLAY INVISIBLE (-2325 4275);
FORCEPROP 2 LAST BOM_COST MIO_CHASSIS
J 0
(-2325 4275);
DISPLAY 1.021277 (-2325 4275);
PAINT ORANGE (-2325 4275);
DISPLAY INVISIBLE (-2325 4275);
FORCEPROP 2 LAST ROOM MIO_CHASSIS
J 0
(-2325 4225);
DISPLAY 1.021277 (-2325 4225);
PAINT ORANGE (-2325 4225);
DISPLAY INVISIBLE (-2325 4225);
FORCEPROP 1 LAST PATH I13
J 0
(-2325 4225);
DISPLAY 0.978723 (-2325 4225);
PAINT WHITE (-2325 4225);
DISPLAY INVISIBLE (-2325 4225);
FORCEPROP 0 LAST SEC 1
J 0
(-2325 4225);
DISPLAY 0.680851 (-2325 4225);
PAINT MONO (-2325 4225);
DISPLAY INVISIBLE (-2325 4225);
FORCEPROP 2 LAST CDS_LOCATION R1L26
J 0
(-2325 4125);
DISPLAY 0.617021 (-2325 4125);
PAINT AQUA (-2325 4125);
DISPLAY INVISIBLE (-2325 4125);
FORCEPROP 2 LAST CDS_LIB mstr_discrete
J 0
(-2275 4075);
PAINT ORANGE (-2275 4075);
DISPLAY INVISIBLE (-2275 4075);
FORCEADD OFFPAGE..2
(-1350 4075);
FORCEPROP 2 LAST $XR2 190 
J 0
(-1161 4039);
DISPLAY 0.638298 (-1161 4039);
PAINT MONO (-1161 4039);
FORCEPROP 2 LAST $XR1 145 
J 0
(-1041 4075);
DISPLAY 0.638298 (-1041 4075);
PAINT MONO (-1041 4075);
FORCEPROP 2 LAST $XR0 119 
J 0
(-1161 4075);
DISPLAY 0.638298 (-1161 4075);
PAINT MONO (-1161 4075);
FORCEPROP 2 LAST PATH I14
J 0
(-1300 4150);
DISPLAY 1.021277 (-1300 4150);
PAINT ORANGE (-1300 4150);
DISPLAY INVISIBLE (-1300 4150);
FORCEPROP 2 LAST CDS_LIB mstr_standard
J 0
(-1350 4075);
PAINT ORANGE (-1350 4075);
DISPLAY INVISIBLE (-1350 4075);
FORCEPROP 1 LAST OFFPAGE TRUE
J 0
(-1025 3950);
DISPLAY 0.872340 (-1025 3950);
PAINT GREEN (-1025 3950);
DISPLAY INVISIBLE (-1025 3950);
FORCEPROP 1 LAST COMMENT_BODY TRUE
J 0
(-1395 3980);
DISPLAY 0.872340 (-1395 3980);
PAINT GREEN (-1395 3980);
DISPLAY INVISIBLE (-1395 3980);
FORCEADD CAP_A..1
(-4925 2550);
FORCEPROP 1 LASTPIN (-4925 2450) $PN 2
J 0
(-4915 2430);
DISPLAY 0.617021 (-4915 2430);
PAINT ORANGE (-4915 2430);
FORCEPROP 1 LAST VALUE 1.0UF
J 0
(-4875 2600);
DISPLAY 0.617021 (-4875 2600);
PAINT SKYBLUE (-4875 2600);
FORCEPROP 1 LAST LOCATION C1L10
J 0
(-4875 2650);
DISPLAY 0.617021 (-4875 2650);
PAINT AQUA (-4875 2650);
FORCEPROP 1 LASTPIN (-4925 2650) $PN 1
J 0
(-4915 2630);
DISPLAY 0.617021 (-4915 2630);
PAINT ORANGE (-4915 2630);
FORCEPROP 1 LAST VOLTAGE 6.3V
J 0
(-4875 2550);
DISPLAY 0.617021 (-4875 2550);
PAINT SKYBLUE (-4875 2550);
FORCEPROP 1 LAST PACK_TYPE 0402V
J 0
(-4875 2350);
DISPLAY 0.617021 (-4875 2350);
PAINT SKYBLUE (-4875 2350);
FORCEPROP 1 LAST PART_NUMBER D97712-004
J 0
(-4875 2400);
DISPLAY 0.617021 (-4875 2400);
PAINT BLUE (-4875 2400);
FORCEPROP 1 LAST MATERIAL X6S
J 0
(-4875 2450);
DISPLAY 0.617021 (-4875 2450);
PAINT SKYBLUE (-4875 2450);
FORCEPROP 1 LAST TOLERANCE 10%
J 0
(-4875 2500);
DISPLAY 0.617021 (-4875 2500);
PAINT SKYBLUE (-4875 2500);
FORCEPROP 2 LAST SEC 1
J 0
(-4875 2700);
DISPLAY 0.680851 (-4875 2700);
PAINT MONO (-4875 2700);
DISPLAY INVISIBLE (-4875 2700);
FORCEPROP 1 LAST PATH I19
J 0
(-4875 2700);
DISPLAY 0.978723 (-4875 2700);
PAINT WHITE (-4875 2700);
DISPLAY INVISIBLE (-4875 2700);
FORCEPROP 2 LAST ROOM MIO_CHASSIS
J 0
(-4875 2700);
DISPLAY 1.021277 (-4875 2700);
PAINT ORANGE (-4875 2700);
DISPLAY INVISIBLE (-4875 2700);
FORCEPROP 2 LAST BOM_COST MIO_CHASSIS
J 0
(-4875 2750);
DISPLAY 1.021277 (-4875 2750);
PAINT ORANGE (-4875 2750);
DISPLAY INVISIBLE (-4875 2750);
FORCEPROP 2 LAST CDS_SEC 1
J 0
(-4875 2700);
PAINT ORANGE (-4875 2700);
DISPLAY INVISIBLE (-4875 2700);
FORCEPROP 2 LAST SEC_TYPE 0402V
J 0
(-4875 2750);
DISPLAY 1.021277 (-4875 2750);
PAINT ORANGE (-4875 2750);
DISPLAY INVISIBLE (-4875 2750);
FORCEPROP 2 LAST CDS_LOCATION C1L10
J 0
(-4875 2650);
DISPLAY 0.617021 (-4875 2650);
PAINT AQUA (-4875 2650);
DISPLAY INVISIBLE (-4875 2650);
FORCEPROP 2 LAST CDS_LIB dev_discrete
J 0
(-4925 2550);
PAINT ORANGE (-4925 2550);
DISPLAY INVISIBLE (-4925 2550);
FORCEADD GND..1
(-4925 2275);
FORCEPROP 3 LASTPIN (-4925 2325) SIG_NAME GND\g
J 0
(-4915 2335);
DISPLAY 0.659574 (-4915 2335);
PAINT MONO (-4915 2335);
DISPLAY INVISIBLE (-4915 2335);
FORCEPROP 2 LAST CDS_LIB mstr_symbols
J 0
(-4925 2275);
PAINT ORANGE (-4925 2275);
DISPLAY INVISIBLE (-4925 2275);
FORCEPROP 1 LAST PATH I20
J 0
(-4850 2275);
DISPLAY 0.872340 (-4850 2275);
PAINT AQUA (-4850 2275);
DISPLAY INVISIBLE (-4850 2275);
FORCEPROP 1 LAST VOLTAGE 0.0V
J 0
(-4970 2232);
DISPLAY 0.340426 (-4970 2232);
PAINT SKYBLUE (-4970 2232);
DISPLAY INVISIBLE (-4970 2232);
FORCEPROP 1 LAST SIZE 1B
J 0
(-4850 2225);
DISPLAY 0.872340 (-4850 2225);
PAINT AQUA (-4850 2225);
DISPLAY INVISIBLE (-4850 2225);
FORCEPROP 1 LAST BODY_TYPE PLUMBING
J 0
(-4970 2232);
DISPLAY 0.340426 (-4970 2232);
PAINT GREEN (-4970 2232);
DISPLAY INVISIBLE (-4970 2232);
FORCEPROP 1 LAST HDL_POWER GND
J 0
(-4925 2425);
DISPLAY 0.872340 (-4925 2425);
PAINT GREEN (-4925 2425);
DISPLAY INVISIBLE (-4925 2425);
FORCEADD P3V3_STBY..1
(-5875 3400);
FORCEPROP 3 LASTPIN (-5875 3350) SIG_NAME P3V3_STBY\g
J 0
(-5865 3360);
DISPLAY 0.659574 (-5865 3360);
PAINT MONO (-5865 3360);
DISPLAY INVISIBLE (-5865 3360);
FORCEPROP 2 LAST CDS_LIB mstr_symbols
J 0
(-5875 3400);
PAINT ORANGE (-5875 3400);
DISPLAY INVISIBLE (-5875 3400);
FORCEPROP 1 LAST SIZE 1B
J 0
(-5830 3422);
DISPLAY 0.340426 (-5830 3422);
PAINT GREEN (-5830 3422);
DISPLAY INVISIBLE (-5830 3422);
FORCEPROP 1 LAST PATH I21
J 0
(-5830 3402);
DISPLAY 0.340426 (-5830 3402);
PAINT GREEN (-5830 3402);
DISPLAY INVISIBLE (-5830 3402);
FORCEPROP 1 LAST VOLTAGE 3.3V
J 0
(-5920 3357);
DISPLAY 0.340426 (-5920 3357);
PAINT SKYBLUE (-5920 3357);
DISPLAY INVISIBLE (-5920 3357);
FORCEPROP 1 LAST BODY_TYPE PLUMBING
J 0
(-5920 3357);
DISPLAY 0.340426 (-5920 3357);
PAINT GREEN (-5920 3357);
DISPLAY INVISIBLE (-5920 3357);
FORCEPROP 1 LAST HDL_POWER P3V3_STBY
J 0
(-6175 3275);
DISPLAY 0.872340 (-6175 3275);
PAINT ORANGE (-6175 3275);
DISPLAY INVISIBLE (-6175 3275);
FORCEADD RES..1
(-5600 2775);
FORCEPROP 1 LAST TOLERANCE 1%
J 0
(-5600 2675);
DISPLAY 0.617021 (-5600 2675);
PAINT SKYBLUE (-5600 2675);
FORCEPROP 1 LASTPIN (-5500 2775) $PN 2
J 0
(-5538 2787);
DISPLAY 0.617021 (-5538 2787);
PAINT ORANGE (-5538 2787);
FORCEPROP 1 LAST LOCATION R1L22
J 0
(-5650 2825);
DISPLAY 0.617021 (-5650 2825);
PAINT AQUA (-5650 2825);
FORCEPROP 1 LASTPIN (-5700 2775) $PN 1
J 0
(-5688 2787);
DISPLAY 0.617021 (-5688 2787);
PAINT ORANGE (-5688 2787);
FORCEPROP 1 LAST VALUE 200.0
J 2
(-5625 2675);
DISPLAY 0.617021 (-5625 2675);
PAINT SKYBLUE (-5625 2675);
FORCEPROP 1 LAST WATTAGE 1/16W
J 2
(-5625 2625);
DISPLAY 0.617021 (-5625 2625);
PAINT SKYBLUE (-5625 2625);
FORCEPROP 1 LAST MATERIAL CHIP
J 0
(-5600 2625);
DISPLAY 0.617021 (-5600 2625);
PAINT SKYBLUE (-5600 2625);
FORCEPROP 1 LAST PACK_TYPE 0402
J 0
(-5350 2625);
DISPLAY 0.617021 (-5350 2625);
PAINT SKYBLUE (-5350 2625);
FORCEPROP 1 LAST PART_NUMBER G21796-004
J 0
(-5650 2875);
DISPLAY 0.617021 (-5650 2875);
PAINT BLUE (-5650 2875);
FORCEPROP 2 LAST CDS_LIB mstr_discrete
J 0
(-5600 2775);
PAINT ORANGE (-5600 2775);
DISPLAY INVISIBLE (-5600 2775);
FORCEPROP 2 LAST BOM_COST MIO_CHASSIS
J 0
(-5650 2975);
DISPLAY 1.021277 (-5650 2975);
PAINT ORANGE (-5650 2975);
DISPLAY INVISIBLE (-5650 2975);
FORCEPROP 2 LAST SEC_TYPE 0402
J 0
(-5650 2975);
DISPLAY 1.021277 (-5650 2975);
PAINT ORANGE (-5650 2975);
DISPLAY INVISIBLE (-5650 2975);
FORCEPROP 0 LAST SEC 1
J 0
(-5650 2925);
DISPLAY 0.680851 (-5650 2925);
PAINT MONO (-5650 2925);
DISPLAY INVISIBLE (-5650 2925);
FORCEPROP 2 LAST CDS_LOCATION R1L22
J 0
(-5650 2825);
DISPLAY 0.617021 (-5650 2825);
PAINT AQUA (-5650 2825);
DISPLAY INVISIBLE (-5650 2825);
FORCEPROP 1 LAST PATH I22
J 0
(-5650 2925);
DISPLAY 0.978723 (-5650 2925);
PAINT WHITE (-5650 2925);
DISPLAY INVISIBLE (-5650 2925);
FORCEPROP 2 LAST ROOM MIO_CHASSIS
J 0
(-5650 2925);
DISPLAY 1.021277 (-5650 2925);
PAINT ORANGE (-5650 2925);
DISPLAY INVISIBLE (-5650 2925);
FORCEADD GND..1
(-7625 2250);
FORCEPROP 3 LASTPIN (-7625 2300) SIG_NAME GND\g
J 0
(-7615 2310);
DISPLAY 0.659574 (-7615 2310);
PAINT MONO (-7615 2310);
DISPLAY INVISIBLE (-7615 2310);
FORCEPROP 1 LAST PATH I27
J 0
(-7550 2250);
DISPLAY 0.872340 (-7550 2250);
PAINT AQUA (-7550 2250);
DISPLAY INVISIBLE (-7550 2250);
FORCEPROP 2 LAST CDS_LIB mstr_symbols
J 0
(-7625 2250);
PAINT ORANGE (-7625 2250);
DISPLAY INVISIBLE (-7625 2250);
FORCEPROP 1 LAST SIZE 1B
J 0
(-7550 2200);
DISPLAY 0.872340 (-7550 2200);
PAINT AQUA (-7550 2200);
DISPLAY INVISIBLE (-7550 2200);
FORCEPROP 1 LAST VOLTAGE 0.0V
J 0
(-7670 2207);
DISPLAY 0.340426 (-7670 2207);
PAINT SKYBLUE (-7670 2207);
DISPLAY INVISIBLE (-7670 2207);
FORCEPROP 1 LAST BODY_TYPE PLUMBING
J 0
(-7670 2207);
DISPLAY 0.340426 (-7670 2207);
PAINT GREEN (-7670 2207);
DISPLAY INVISIBLE (-7670 2207);
FORCEPROP 1 LAST HDL_POWER GND
J 0
(-7625 2400);
DISPLAY 0.872340 (-7625 2400);
PAINT GREEN (-7625 2400);
DISPLAY INVISIBLE (-7625 2400);
FORCEADD OFFPAGE..1
(-7550 1925);
FORCEPROP 2 LAST $XR3 190 
J 0
(-8162 1925);
DISPLAY 0.638298 (-8162 1925);
PAINT MONO (-8162 1925);
FORCEPROP 2 LAST $XR2 247 
J 0
(-8042 1925);
DISPLAY 0.638298 (-8042 1925);
PAINT MONO (-8042 1925);
FORCEPROP 2 LAST $XR1 155 
J 0
(-7922 1925);
DISPLAY 0.638298 (-7922 1925);
PAINT MONO (-7922 1925);
FORCEPROP 2 LAST $XR0 111 
J 0
(-7802 1925);
DISPLAY 0.638298 (-7802 1925);
PAINT MONO (-7802 1925);
FORCEPROP 2 LAST CDS_LIB mstr_standard
J 0
(-7550 1925);
PAINT ORANGE (-7550 1925);
DISPLAY INVISIBLE (-7550 1925);
FORCEPROP 2 LAST PATH I28
J 0
(-7500 2000);
DISPLAY 1.021277 (-7500 2000);
PAINT ORANGE (-7500 2000);
DISPLAY INVISIBLE (-7500 2000);
FORCEPROP 1 LAST OFFPAGE TRUE
J 0
(-7225 1800);
DISPLAY 0.872340 (-7225 1800);
PAINT GREEN (-7225 1800);
DISPLAY INVISIBLE (-7225 1800);
FORCEPROP 1 LAST COMMENT_BODY TRUE
J 0
(-7425 1825);
DISPLAY 0.872340 (-7425 1825);
PAINT GREEN (-7425 1825);
DISPLAY INVISIBLE (-7425 1825);
FORCEADD GND..1
(-7675 3650);
FORCEPROP 3 LASTPIN (-7675 3700) SIG_NAME GND\g
J 0
(-7665 3710);
DISPLAY 0.659574 (-7665 3710);
PAINT MONO (-7665 3710);
DISPLAY INVISIBLE (-7665 3710);
FORCEPROP 2 LAST CDS_LIB mstr_symbols
J 0
(-7675 3650);
PAINT ORANGE (-7675 3650);
DISPLAY INVISIBLE (-7675 3650);
FORCEPROP 1 LAST PATH I3
J 0
(-7600 3650);
DISPLAY 0.872340 (-7600 3650);
PAINT AQUA (-7600 3650);
DISPLAY INVISIBLE (-7600 3650);
FORCEPROP 1 LAST SIZE 1B
J 0
(-7600 3600);
DISPLAY 0.872340 (-7600 3600);
PAINT AQUA (-7600 3600);
DISPLAY INVISIBLE (-7600 3600);
FORCEPROP 1 LAST VOLTAGE 0.0V
J 0
(-7720 3607);
DISPLAY 0.340426 (-7720 3607);
PAINT SKYBLUE (-7720 3607);
DISPLAY INVISIBLE (-7720 3607);
FORCEPROP 1 LAST BODY_TYPE PLUMBING
J 0
(-7720 3607);
DISPLAY 0.340426 (-7720 3607);
PAINT GREEN (-7720 3607);
DISPLAY INVISIBLE (-7720 3607);
FORCEPROP 1 LAST HDL_POWER GND
J 0
(-7675 3800);
DISPLAY 0.872340 (-7675 3800);
PAINT GREEN (-7675 3800);
DISPLAY INVISIBLE (-7675 3800);
FORCEADD CAP_A..1
(-2950 4450);
FORCEPROP 1 LAST PART_NUMBER A36096-030
J 0
(-2900 4300);
DISPLAY 0.617021 (-2900 4300);
PAINT BLUE (-2900 4300);
FORCEPROP 1 LAST VALUE 0.1UF
J 0
(-2900 4500);
DISPLAY 0.617021 (-2900 4500);
PAINT SKYBLUE (-2900 4500);
FORCEPROP 1 LAST VOLTAGE 16V
J 0
(-2900 4450);
DISPLAY 0.617021 (-2900 4450);
PAINT SKYBLUE (-2900 4450);
FORCEPROP 1 LASTPIN (-2950 4550) $PN 1
J 0
(-2940 4530);
DISPLAY 0.617021 (-2940 4530);
PAINT ORANGE (-2940 4530);
FORCEPROP 1 LAST PACK_TYPE 0402V
J 0
(-2900 4250);
DISPLAY 0.617021 (-2900 4250);
PAINT SKYBLUE (-2900 4250);
FORCEPROP 1 LASTPIN (-2950 4350) $PN 2
J 0
(-2940 4330);
DISPLAY 0.617021 (-2940 4330);
PAINT ORANGE (-2940 4330);
FORCEPROP 1 LAST LOCATION C1L17
J 0
(-2900 4550);
DISPLAY 0.617021 (-2900 4550);
PAINT AQUA (-2900 4550);
FORCEPROP 1 LAST MATERIAL X7R
J 0
(-2900 4350);
DISPLAY 0.617021 (-2900 4350);
PAINT SKYBLUE (-2900 4350);
FORCEPROP 1 LAST TOLERANCE 10%
J 0
(-2900 4400);
DISPLAY 0.617021 (-2900 4400);
PAINT SKYBLUE (-2900 4400);
FORCEPROP 1 LAST PATH I37
J 0
(-2900 4600);
DISPLAY 0.978723 (-2900 4600);
PAINT WHITE (-2900 4600);
DISPLAY INVISIBLE (-2900 4600);
FORCEPROP 2 LAST ROOM MIO_CHASSIS
J 0
(-2900 4600);
DISPLAY 1.021277 (-2900 4600);
PAINT ORANGE (-2900 4600);
DISPLAY INVISIBLE (-2900 4600);
FORCEPROP 2 LAST CDS_LOCATION C1L17
J 0
(-2900 4550);
DISPLAY 0.617021 (-2900 4550);
PAINT AQUA (-2900 4550);
DISPLAY INVISIBLE (-2900 4550);
FORCEPROP 2 LAST BOM_COST MIO_CHASSIS
J 0
(-2900 4650);
DISPLAY 1.021277 (-2900 4650);
PAINT ORANGE (-2900 4650);
DISPLAY INVISIBLE (-2900 4650);
FORCEPROP 2 LAST CDS_SEC 1
J 0
(-2900 4600);
PAINT ORANGE (-2900 4600);
DISPLAY INVISIBLE (-2900 4600);
FORCEPROP 2 LAST SEC_TYPE 0402V
J 0
(-2900 4650);
DISPLAY 1.021277 (-2900 4650);
PAINT ORANGE (-2900 4650);
DISPLAY INVISIBLE (-2900 4650);
FORCEPROP 2 LAST SEC 1
J 0
(-2900 4600);
DISPLAY 0.680851 (-2900 4600);
PAINT MONO (-2900 4600);
DISPLAY INVISIBLE (-2900 4600);
FORCEPROP 2 LAST CDS_LIB dev_discrete
J 0
(-2950 4450);
PAINT ORANGE (-2950 4450);
DISPLAY INVISIBLE (-2950 4450);
FORCEADD CAP_A..1
(-2975 3000);
FORCEPROP 1 LAST VOLTAGE 16V
J 0
(-2925 3000);
DISPLAY 0.617021 (-2925 3000);
PAINT SKYBLUE (-2925 3000);
FORCEPROP 1 LAST MATERIAL X7R
J 0
(-2925 2900);
DISPLAY 0.617021 (-2925 2900);
PAINT SKYBLUE (-2925 2900);
FORCEPROP 1 LAST PART_NUMBER A36096-030
J 0
(-2925 2850);
DISPLAY 0.617021 (-2925 2850);
PAINT BLUE (-2925 2850);
FORCEPROP 1 LAST PACK_TYPE 0402V
J 0
(-2925 2800);
DISPLAY 0.617021 (-2925 2800);
PAINT SKYBLUE (-2925 2800);
FORCEPROP 1 LAST TOLERANCE 10%
J 0
(-2925 2950);
DISPLAY 0.617021 (-2925 2950);
PAINT SKYBLUE (-2925 2950);
FORCEPROP 1 LASTPIN (-2975 3100) $PN 1
J 0
(-2965 3080);
DISPLAY 0.617021 (-2965 3080);
PAINT ORANGE (-2965 3080);
FORCEPROP 1 LAST LOCATION C1L9
J 0
(-2925 3100);
DISPLAY 0.617021 (-2925 3100);
PAINT AQUA (-2925 3100);
FORCEPROP 1 LAST VALUE 0.1UF
J 0
(-2925 3050);
DISPLAY 0.617021 (-2925 3050);
PAINT SKYBLUE (-2925 3050);
FORCEPROP 1 LASTPIN (-2975 2900) $PN 2
J 0
(-2965 2880);
DISPLAY 0.617021 (-2965 2880);
PAINT ORANGE (-2965 2880);
FORCEPROP 2 LAST BOM_COST MIO_CHASSIS
J 0
(-2925 3200);
DISPLAY 1.021277 (-2925 3200);
PAINT ORANGE (-2925 3200);
DISPLAY INVISIBLE (-2925 3200);
FORCEPROP 2 LAST SEC_TYPE 0402V
J 0
(-2925 3200);
DISPLAY 1.021277 (-2925 3200);
PAINT ORANGE (-2925 3200);
DISPLAY INVISIBLE (-2925 3200);
FORCEPROP 1 LAST PATH I38
J 0
(-2925 3150);
DISPLAY 0.978723 (-2925 3150);
PAINT WHITE (-2925 3150);
DISPLAY INVISIBLE (-2925 3150);
FORCEPROP 2 LAST ROOM MIO_CHASSIS
J 0
(-2925 3150);
DISPLAY 1.021277 (-2925 3150);
PAINT ORANGE (-2925 3150);
DISPLAY INVISIBLE (-2925 3150);
FORCEPROP 2 LAST CDS_LOCATION C1L9
J 0
(-2925 3100);
DISPLAY 0.617021 (-2925 3100);
PAINT AQUA (-2925 3100);
DISPLAY INVISIBLE (-2925 3100);
FORCEPROP 2 LAST CDS_LIB dev_discrete
J 0
(-2975 3000);
PAINT ORANGE (-2975 3000);
DISPLAY INVISIBLE (-2975 3000);
FORCEPROP 2 LAST CDS_SEC 1
J 0
(-2925 3150);
PAINT ORANGE (-2925 3150);
DISPLAY INVISIBLE (-2925 3150);
FORCEPROP 2 LAST SEC 1
J 0
(-2925 3150);
DISPLAY 0.680851 (-2925 3150);
PAINT MONO (-2925 3150);
DISPLAY INVISIBLE (-2925 3150);
FORCEADD RES..1
(-5650 4175);
FORCEPROP 1 LAST PACK_TYPE 0402
J 0
(-5400 4025);
DISPLAY 0.617021 (-5400 4025);
PAINT SKYBLUE (-5400 4025);
FORCEPROP 1 LAST MATERIAL CHIP
J 0
(-5650 4025);
DISPLAY 0.617021 (-5650 4025);
PAINT SKYBLUE (-5650 4025);
FORCEPROP 1 LASTPIN (-5550 4175) $PN 2
J 0
(-5588 4187);
DISPLAY 0.617021 (-5588 4187);
PAINT ORANGE (-5588 4187);
FORCEPROP 1 LAST LOCATION R1L31
J 0
(-5700 4225);
DISPLAY 0.617021 (-5700 4225);
PAINT AQUA (-5700 4225);
FORCEPROP 1 LAST PART_NUMBER G21796-004
J 0
(-5700 4275);
DISPLAY 0.617021 (-5700 4275);
PAINT BLUE (-5700 4275);
FORCEPROP 1 LAST VALUE 200.0
J 2
(-5675 4075);
DISPLAY 0.617021 (-5675 4075);
PAINT SKYBLUE (-5675 4075);
FORCEPROP 1 LAST WATTAGE 1/16W
J 2
(-5675 4025);
DISPLAY 0.617021 (-5675 4025);
PAINT SKYBLUE (-5675 4025);
FORCEPROP 1 LASTPIN (-5750 4175) $PN 1
J 0
(-5738 4187);
DISPLAY 0.617021 (-5738 4187);
PAINT ORANGE (-5738 4187);
FORCEPROP 1 LAST TOLERANCE 1%
J 0
(-5650 4075);
DISPLAY 0.617021 (-5650 4075);
PAINT SKYBLUE (-5650 4075);
FORCEPROP 2 LAST SEC 1
J 0
(-5700 4375);
DISPLAY 0.680851 (-5700 4375);
PAINT MONO (-5700 4375);
DISPLAY INVISIBLE (-5700 4375);
FORCEPROP 2 LAST BOM_COST MIO_CHASSIS
J 0
(-5700 4375);
DISPLAY 1.021277 (-5700 4375);
PAINT ORANGE (-5700 4375);
DISPLAY INVISIBLE (-5700 4375);
FORCEPROP 2 LAST SEC_TYPE 0402
J 0
(-5700 4375);
DISPLAY 1.021277 (-5700 4375);
PAINT ORANGE (-5700 4375);
DISPLAY INVISIBLE (-5700 4375);
FORCEPROP 1 LAST PATH I4
J 0
(-5700 4325);
DISPLAY 0.978723 (-5700 4325);
PAINT WHITE (-5700 4325);
DISPLAY INVISIBLE (-5700 4325);
FORCEPROP 2 LAST ROOM MIO_CHASSIS
J 0
(-5700 4325);
DISPLAY 1.021277 (-5700 4325);
PAINT ORANGE (-5700 4325);
DISPLAY INVISIBLE (-5700 4325);
FORCEPROP 2 LAST CDS_LOCATION R1L31
J 0
(-5700 4225);
DISPLAY 0.617021 (-5700 4225);
PAINT AQUA (-5700 4225);
DISPLAY INVISIBLE (-5700 4225);
FORCEPROP 2 LAST CDS_LIB mstr_discrete
J 0
(-5650 4175);
PAINT ORANGE (-5650 4175);
DISPLAY INVISIBLE (-5650 4175);
FORCEADD CAP_A..1
(-575 3500);
FORCEPROP 1 LASTPIN (-575 3600) $PN 1
J 0
(-565 3580);
DISPLAY 0.617021 (-565 3580);
PAINT ORANGE (-565 3580);
FORCEPROP 1 LAST VOLTAGE 16V
J 0
(-525 3500);
DISPLAY 0.617021 (-525 3500);
PAINT SKYBLUE (-525 3500);
FORCEPROP 1 LAST VALUE 0.1UF
J 0
(-525 3550);
DISPLAY 0.617021 (-525 3550);
PAINT SKYBLUE (-525 3550);
FORCEPROP 1 LAST LOCATION C9A3
J 0
(-525 3600);
DISPLAY 0.617021 (-525 3600);
PAINT AQUA (-525 3600);
FORCEPROP 1 LAST TOLERANCE 10%
J 0
(-525 3450);
DISPLAY 0.617021 (-525 3450);
PAINT SKYBLUE (-525 3450);
FORCEPROP 1 LAST MATERIAL X7R
J 0
(-525 3400);
DISPLAY 0.617021 (-525 3400);
PAINT SKYBLUE (-525 3400);
FORCEPROP 1 LASTPIN (-575 3400) $PN 2
J 0
(-565 3380);
DISPLAY 0.617021 (-565 3380);
PAINT ORANGE (-565 3380);
FORCEPROP 1 LAST PART_NUMBER A36096-030
J 0
(-525 3350);
DISPLAY 0.617021 (-525 3350);
PAINT BLUE (-525 3350);
FORCEPROP 1 LAST PACK_TYPE 0402V
J 0
(-525 3300);
DISPLAY 0.617021 (-525 3300);
PAINT SKYBLUE (-525 3300);
FORCEPROP 2 LAST SEC 1
J 0
(-525 3700);
DISPLAY 0.680851 (-525 3700);
PAINT MONO (-525 3700);
DISPLAY INVISIBLE (-525 3700);
FORCEPROP 2 LAST SEC_TYPE 0402V
J 0
(-525 3700);
DISPLAY 1.021277 (-525 3700);
PAINT ORANGE (-525 3700);
DISPLAY INVISIBLE (-525 3700);
FORCEPROP 2 LAST BOM_COST MIO_CHASSIS
J 0
(-525 3700);
DISPLAY 1.021277 (-525 3700);
PAINT ORANGE (-525 3700);
DISPLAY INVISIBLE (-525 3700);
FORCEPROP 2 LAST ROOM MIO_CHASSIS
J 0
(-525 3650);
DISPLAY 1.021277 (-525 3650);
PAINT ORANGE (-525 3650);
DISPLAY INVISIBLE (-525 3650);
FORCEPROP 1 LAST PATH I40
J 0
(-525 3650);
DISPLAY 0.978723 (-525 3650);
PAINT WHITE (-525 3650);
DISPLAY INVISIBLE (-525 3650);
FORCEPROP 2 LAST CDS_LOCATION C9A3
J 0
(-525 3600);
DISPLAY 0.617021 (-525 3600);
PAINT AQUA (-525 3600);
DISPLAY INVISIBLE (-525 3600);
FORCEPROP 2 LAST CDS_SEC 1
J 0
(-525 3650);
PAINT ORANGE (-525 3650);
DISPLAY INVISIBLE (-525 3650);
FORCEPROP 2 LAST CDS_LIB dev_discrete
J 0
(-575 3500);
PAINT ORANGE (-575 3500);
DISPLAY INVISIBLE (-575 3500);
FORCEADD GND..1
(-2975 2800);
FORCEPROP 3 LASTPIN (-2975 2850) SIG_NAME GND\g
J 0
(-2965 2860);
DISPLAY 0.659574 (-2965 2860);
PAINT MONO (-2965 2860);
DISPLAY INVISIBLE (-2965 2860);
FORCEPROP 2 LAST CDS_LIB mstr_symbols
J 0
(-2975 2800);
PAINT ORANGE (-2975 2800);
DISPLAY INVISIBLE (-2975 2800);
FORCEPROP 1 LAST PATH I41
J 0
(-2900 2800);
DISPLAY 0.872340 (-2900 2800);
PAINT AQUA (-2900 2800);
DISPLAY INVISIBLE (-2900 2800);
FORCEPROP 1 LAST VOLTAGE 0.0V
J 0
(-3020 2757);
DISPLAY 0.340426 (-3020 2757);
PAINT SKYBLUE (-3020 2757);
DISPLAY INVISIBLE (-3020 2757);
FORCEPROP 1 LAST SIZE 1B
J 0
(-2900 2750);
DISPLAY 0.872340 (-2900 2750);
PAINT AQUA (-2900 2750);
DISPLAY INVISIBLE (-2900 2750);
FORCEPROP 1 LAST BODY_TYPE PLUMBING
J 0
(-3020 2757);
DISPLAY 0.340426 (-3020 2757);
PAINT GREEN (-3020 2757);
DISPLAY INVISIBLE (-3020 2757);
FORCEPROP 1 LAST HDL_POWER GND
J 0
(-2975 2950);
DISPLAY 0.872340 (-2975 2950);
PAINT GREEN (-2975 2950);
DISPLAY INVISIBLE (-2975 2950);
FORCEADD GND..1
(-2950 4200);
FORCEPROP 3 LASTPIN (-2950 4250) SIG_NAME GND\g
J 0
(-2940 4260);
DISPLAY 0.659574 (-2940 4260);
PAINT MONO (-2940 4260);
DISPLAY INVISIBLE (-2940 4260);
FORCEPROP 1 LAST PATH I42
J 0
(-2875 4200);
DISPLAY 0.872340 (-2875 4200);
PAINT AQUA (-2875 4200);
DISPLAY INVISIBLE (-2875 4200);
FORCEPROP 1 LAST SIZE 1B
J 0
(-2875 4150);
DISPLAY 0.872340 (-2875 4150);
PAINT AQUA (-2875 4150);
DISPLAY INVISIBLE (-2875 4150);
FORCEPROP 1 LAST VOLTAGE 0.0V
J 0
(-2995 4157);
DISPLAY 0.340426 (-2995 4157);
PAINT SKYBLUE (-2995 4157);
DISPLAY INVISIBLE (-2995 4157);
FORCEPROP 2 LAST CDS_LIB mstr_symbols
J 0
(-2950 4200);
PAINT ORANGE (-2950 4200);
DISPLAY INVISIBLE (-2950 4200);
FORCEPROP 1 LAST BODY_TYPE PLUMBING
J 0
(-2995 4157);
DISPLAY 0.340426 (-2995 4157);
PAINT GREEN (-2995 4157);
DISPLAY INVISIBLE (-2995 4157);
FORCEPROP 1 LAST HDL_POWER GND
J 0
(-2950 4350);
DISPLAY 0.872340 (-2950 4350);
PAINT GREEN (-2950 4350);
DISPLAY INVISIBLE (-2950 4350);
FORCEADD P3V3_STBY..1
(-2950 4700);
FORCEPROP 3 LASTPIN (-2950 4650) SIG_NAME P3V3_STBY\g
J 0
(-2940 4660);
DISPLAY 0.659574 (-2940 4660);
PAINT MONO (-2940 4660);
DISPLAY INVISIBLE (-2940 4660);
FORCEPROP 1 LAST VOLTAGE 3.3V
J 0
(-2995 4657);
DISPLAY 0.340426 (-2995 4657);
PAINT SKYBLUE (-2995 4657);
DISPLAY INVISIBLE (-2995 4657);
FORCEPROP 1 LAST PATH I43
J 0
(-2905 4702);
DISPLAY 0.340426 (-2905 4702);
PAINT GREEN (-2905 4702);
DISPLAY INVISIBLE (-2905 4702);
FORCEPROP 2 LAST CDS_LIB mstr_symbols
J 0
(-2950 4700);
PAINT ORANGE (-2950 4700);
DISPLAY INVISIBLE (-2950 4700);
FORCEPROP 1 LAST SIZE 1B
J 0
(-2905 4722);
DISPLAY 0.340426 (-2905 4722);
PAINT GREEN (-2905 4722);
DISPLAY INVISIBLE (-2905 4722);
FORCEPROP 1 LAST BODY_TYPE PLUMBING
J 0
(-2995 4657);
DISPLAY 0.340426 (-2995 4657);
PAINT GREEN (-2995 4657);
DISPLAY INVISIBLE (-2995 4657);
FORCEPROP 1 LAST HDL_POWER P3V3_STBY
J 0
(-3250 4575);
DISPLAY 0.872340 (-3250 4575);
PAINT ORANGE (-3250 4575);
DISPLAY INVISIBLE (-3250 4575);
FORCEADD P3V3_STBY..1
(-2975 3250);
FORCEPROP 3 LASTPIN (-2975 3200) SIG_NAME P3V3_STBY\g
J 0
(-2965 3210);
DISPLAY 0.659574 (-2965 3210);
PAINT MONO (-2965 3210);
DISPLAY INVISIBLE (-2965 3210);
FORCEPROP 2 LAST CDS_LIB mstr_symbols
J 0
(-2975 3250);
PAINT ORANGE (-2975 3250);
DISPLAY INVISIBLE (-2975 3250);
FORCEPROP 1 LAST VOLTAGE 3.3V
J 0
(-3020 3207);
DISPLAY 0.340426 (-3020 3207);
PAINT SKYBLUE (-3020 3207);
DISPLAY INVISIBLE (-3020 3207);
FORCEPROP 1 LAST SIZE 1B
J 0
(-2930 3272);
DISPLAY 0.340426 (-2930 3272);
PAINT GREEN (-2930 3272);
DISPLAY INVISIBLE (-2930 3272);
FORCEPROP 1 LAST PATH I44
J 0
(-2930 3252);
DISPLAY 0.340426 (-2930 3252);
PAINT GREEN (-2930 3252);
DISPLAY INVISIBLE (-2930 3252);
FORCEPROP 1 LAST BODY_TYPE PLUMBING
J 0
(-3020 3207);
DISPLAY 0.340426 (-3020 3207);
PAINT GREEN (-3020 3207);
DISPLAY INVISIBLE (-3020 3207);
FORCEPROP 1 LAST HDL_POWER P3V3_STBY
J 0
(-3275 3125);
DISPLAY 0.872340 (-3275 3125);
PAINT ORANGE (-3275 3125);
DISPLAY INVISIBLE (-3275 3125);
FORCEADD RES..1
(-4000 1550);
FORCEPROP 1 LAST VALUE 221
J 2
(-4025 1450);
DISPLAY 0.617021 (-4025 1450);
PAINT SKYBLUE (-4025 1450);
FORCEPROP 1 LAST LOCATION R1L33
J 0
(-4050 1600);
DISPLAY 0.617021 (-4050 1600);
PAINT AQUA (-4050 1600);
FORCEPROP 1 LAST PART_NUMBER G21796-271
J 0
(-4050 1650);
DISPLAY 0.617021 (-4050 1650);
PAINT BLUE (-4050 1650);
FORCEPROP 1 LASTPIN (-3900 1550) $PN 2
J 0
(-3938 1562);
DISPLAY 0.617021 (-3938 1562);
PAINT ORANGE (-3938 1562);
FORCEPROP 1 LAST MATERIAL CHIP
J 0
(-4000 1400);
DISPLAY 0.617021 (-4000 1400);
PAINT SKYBLUE (-4000 1400);
FORCEPROP 1 LASTPIN (-4100 1550) $PN 1
J 0
(-4088 1562);
DISPLAY 0.617021 (-4088 1562);
PAINT ORANGE (-4088 1562);
FORCEPROP 1 LAST PACK_TYPE 0402
J 0
(-3900 1450);
DISPLAY 0.617021 (-3900 1450);
PAINT SKYBLUE (-3900 1450);
FORCEPROP 1 LAST TOLERANCE 1.0%
J 0
(-4000 1450);
DISPLAY 0.617021 (-4000 1450);
PAINT SKYBLUE (-4000 1450);
FORCEPROP 1 LAST WATTAGE 1/16W
J 2
(-4025 1400);
DISPLAY 0.617021 (-4025 1400);
PAINT SKYBLUE (-4025 1400);
FORCEPROP 2 LAST SEC_TYPE 0402
J 0
(-4050 1750);
DISPLAY 1.021277 (-4050 1750);
PAINT ORANGE (-4050 1750);
DISPLAY INVISIBLE (-4050 1750);
FORCEPROP 2 LAST BOM_COST MIO_CHASSIS
J 0
(-4050 1750);
DISPLAY 1.021277 (-4050 1750);
PAINT ORANGE (-4050 1750);
DISPLAY INVISIBLE (-4050 1750);
FORCEPROP 2 LAST CDS_LIB mstr_discrete
J 0
(-4000 1550);
PAINT ORANGE (-4000 1550);
DISPLAY INVISIBLE (-4000 1550);
FORCEPROP 2 LAST ROOM MIO_CHASSIS
J 0
(-4050 1700);
DISPLAY 1.021277 (-4050 1700);
PAINT ORANGE (-4050 1700);
DISPLAY INVISIBLE (-4050 1700);
FORCEPROP 0 LAST SEC 1
J 0
(-4050 1700);
DISPLAY 0.680851 (-4050 1700);
PAINT MONO (-4050 1700);
DISPLAY INVISIBLE (-4050 1700);
FORCEPROP 2 LAST CDS_LOCATION R1L33
J 0
(-4050 1600);
DISPLAY 0.617021 (-4050 1600);
PAINT AQUA (-4050 1600);
DISPLAY INVISIBLE (-4050 1600);
FORCEPROP 1 LAST PATH I45
J 0
(-4050 1700);
DISPLAY 0.978723 (-4050 1700);
PAINT WHITE (-4050 1700);
DISPLAY INVISIBLE (-4050 1700);
FORCEADD FET_N..8
(-5025 1175);
FORCEPROP 1 LAST PART_NUMBER C79254-001
J 0
(-4825 975);
DISPLAY 0.617021 (-4825 975);
PAINT BLUE (-4825 975);
FORCEPROP 1 LAST LOCATION Q9A3
J 0
(-4825 1175);
DISPLAY 0.617021 (-4825 1175);
PAINT AQUA (-4825 1175);
FORCEPROP 1 LAST VALUE 2N7002
J 0
(-4825 1125);
DISPLAY 0.617021 (-4825 1125);
PAINT SKYBLUE (-4825 1125);
FORCEPROP 1 LAST MATERIAL FET
J 0
(-4825 1075);
DISPLAY 0.617021 (-4825 1075);
PAINT SKYBLUE (-4825 1075);
FORCEPROP 1 LASTPIN (-5025 975) $PN 2
J 2
(-4967 975);
DISPLAY 0.617021 (-4967 975);
PAINT WHITE (-4967 975);
FORCEPROP 1 LASTPIN (-5225 1075) $PN 1
J 2
(-5222 1090);
DISPLAY 0.617021 (-5222 1090);
PAINT WHITE (-5222 1090);
FORCEPROP 1 LASTPIN (-5025 1375) $PN 3
J 2
(-4972 1340);
DISPLAY 0.617021 (-4972 1340);
PAINT WHITE (-4972 1340);
FORCEPROP 1 LAST PACK_TYPE SOT23LF
J 0
(-4825 1025);
DISPLAY 0.978723 (-4825 1025);
PAINT SKYBLUE (-4825 1025);
DISPLAY INVISIBLE (-4825 1025);
FORCEPROP 2 LAST SEC_TYPE SOT23LF
J 0
(-4825 1275);
DISPLAY 1.021277 (-4825 1275);
PAINT ORANGE (-4825 1275);
DISPLAY INVISIBLE (-4825 1275);
FORCEPROP 2 LAST BOM_COST MIO_CHASSIS
J 0
(-4825 1275);
DISPLAY 1.021277 (-4825 1275);
PAINT ORANGE (-4825 1275);
DISPLAY INVISIBLE (-4825 1275);
FORCEPROP 2 LAST SEC 1
J 0
(-4825 1275);
DISPLAY 0.680851 (-4825 1275);
PAINT MONO (-4825 1275);
DISPLAY INVISIBLE (-4825 1275);
FORCEPROP 2 LAST CDS_LOCATION Q9A3
J 0
(-4825 1175);
DISPLAY 0.617021 (-4825 1175);
PAINT AQUA (-4825 1175);
DISPLAY INVISIBLE (-4825 1175);
FORCEPROP 1 LAST PATH I49
J 0
(-4825 1225);
DISPLAY 0.978723 (-4825 1225);
PAINT BLUE (-4825 1225);
DISPLAY INVISIBLE (-4825 1225);
FORCEPROP 2 LAST ROOM MIO_CHASSIS
J 0
(-4825 1225);
DISPLAY 1.021277 (-4825 1225);
PAINT ORANGE (-4825 1225);
DISPLAY INVISIBLE (-4825 1225);
FORCEPROP 2 LAST CDS_LIB mstr_discrete
J 0
(-5025 1175);
PAINT ORANGE (-5025 1175);
DISPLAY INVISIBLE (-5025 1175);
FORCEADD RES..2
(-5925 4475);
FORCEPROP 1 LAST PART_NUMBER G21796-072
J 0
(-5885 4350);
DISPLAY 0.617021 (-5885 4350);
PAINT BLUE (-5885 4350);
FORCEPROP 1 LAST PACK_TYPE 0402
J 0
(-5885 4300);
DISPLAY 0.617021 (-5885 4300);
PAINT SKYBLUE (-5885 4300);
FORCEPROP 1 LAST WATTAGE 1/16W
J 0
(-5885 4450);
DISPLAY 0.617021 (-5885 4450);
PAINT SKYBLUE (-5885 4450);
FORCEPROP 1 LAST MATERIAL CHIP
J 0
(-5885 4400);
DISPLAY 0.617021 (-5885 4400);
PAINT SKYBLUE (-5885 4400);
FORCEPROP 1 LAST TOLERANCE 1%
J 0
(-5880 4500);
DISPLAY 0.617021 (-5880 4500);
PAINT SKYBLUE (-5880 4500);
FORCEPROP 1 LAST VALUE 4.75K
J 0
(-5880 4550);
DISPLAY 0.617021 (-5880 4550);
PAINT SKYBLUE (-5880 4550);
FORCEPROP 1 LASTPIN (-5925 4575) $PN 1
J 0
(-5920 4537);
DISPLAY 0.617021 (-5920 4537);
PAINT ORANGE (-5920 4537);
FORCEPROP 1 LASTPIN (-5925 4375) $PN 2
J 0
(-5920 4385);
DISPLAY 0.617021 (-5920 4385);
PAINT ORANGE (-5920 4385);
FORCEPROP 1 LAST LOCATION R1L27
J 0
(-5880 4600);
DISPLAY 0.617021 (-5880 4600);
PAINT AQUA (-5880 4600);
FORCEPROP 2 LAST ROOM MIO_CHASSIS
J 0
(-5875 4650);
DISPLAY 1.021277 (-5875 4650);
PAINT ORANGE (-5875 4650);
DISPLAY INVISIBLE (-5875 4650);
FORCEPROP 1 LAST PATH I5
J 0
(-5875 4650);
DISPLAY 0.978723 (-5875 4650);
PAINT WHITE (-5875 4650);
DISPLAY INVISIBLE (-5875 4650);
FORCEPROP 0 LAST SEC 1
J 0
(-5875 4650);
DISPLAY 0.680851 (-5875 4650);
PAINT MONO (-5875 4650);
DISPLAY INVISIBLE (-5875 4650);
FORCEPROP 2 LAST SEC_TYPE 0402
J 0
(-5875 4700);
DISPLAY 1.021277 (-5875 4700);
PAINT ORANGE (-5875 4700);
DISPLAY INVISIBLE (-5875 4700);
FORCEPROP 2 LAST BOM_COST MIO_CHASSIS
J 0
(-5875 4700);
DISPLAY 1.021277 (-5875 4700);
PAINT ORANGE (-5875 4700);
DISPLAY INVISIBLE (-5875 4700);
FORCEPROP 2 LAST CDS_LOCATION R1L27
J 0
(-5880 4600);
DISPLAY 0.617021 (-5880 4600);
PAINT AQUA (-5880 4600);
DISPLAY INVISIBLE (-5880 4600);
FORCEPROP 2 LAST CDS_LIB mstr_discrete
J 0
(-5925 4475);
PAINT ORANGE (-5925 4475);
DISPLAY INVISIBLE (-5925 4475);
FORCEADD LED..3
(-1700 1025);
FORCEPROP 2 LASTPIN (-1800 1025) $PN 1
J 2
(-1810 1035);
DISPLAY 0.617021 (-1810 1035);
PAINT MONO (-1810 1035);
FORCEPROP 1 LAST LOCATION DS9A1
J 0
(-1800 1225);
DISPLAY 0.617021 (-1800 1225);
PAINT AQUA (-1800 1225);
FORCEPROP 1 LAST MATERIAL IC
J 0
(-1800 1175);
DISPLAY 0.617021 (-1800 1175);
PAINT SKYBLUE (-1800 1175);
FORCEPROP 1 LAST COLOR BLUE
J 0
(-1800 1125);
DISPLAY 0.617021 (-1800 1125);
PAINT BLUE (-1800 1125);
FORCEPROP 2 LASTPIN (-1600 1025) $PN 2
J 0
(-1590 1035);
DISPLAY 0.617021 (-1590 1035);
PAINT MONO (-1590 1035);
FORCEPROP 1 LAST PART_NUMBER C96565-012
J 0
(-1800 875);
DISPLAY 0.617021 (-1800 875);
PAINT BLUE (-1800 875);
FORCEPROP 1 LAST PATH I50
J 0
(-1350 1175);
DISPLAY 0.978723 (-1350 1175);
PAINT BLUE (-1350 1175);
DISPLAY INVISIBLE (-1350 1175);
FORCEPROP 2 LAST CDS_LIB mstr_discrete
J 0
(-1700 1025);
PAINT MONO (-1700 1025);
DISPLAY INVISIBLE (-1700 1025);
FORCEPROP 1 LAST PACK_TYPE 1NC
J 0
(-1800 1275);
DISPLAY 0.978723 (-1800 1275);
PAINT SKYBLUE (-1800 1275);
DISPLAY INVISIBLE (-1800 1275);
FORCEPROP 2 LAST BOM_COST MIO_CHASSIS
J 0
(-1800 1325);
DISPLAY 1.021277 (-1800 1325);
PAINT ORANGE (-1800 1325);
DISPLAY INVISIBLE (-1800 1325);
FORCEPROP 2 LAST CDS_SEC 1
J 0
(-1800 1275);
PAINT MONO (-1800 1275);
DISPLAY INVISIBLE (-1800 1275);
FORCEPROP 2 LAST $SEC 1
J 0
(-1800 1275);
PAINT MONO (-1800 1275);
DISPLAY INVISIBLE (-1800 1275);
FORCEPROP 2 LAST CDS_LOCATION DS9A1
J 0
(-1800 1225);
DISPLAY 0.617021 (-1800 1225);
PAINT AQUA (-1800 1225);
DISPLAY INVISIBLE (-1800 1225);
FORCEPROP 2 LAST ROOM MIO_CHASSIS
J 0
(-1800 1275);
DISPLAY 1.021277 (-1800 1275);
PAINT ORANGE (-1800 1275);
DISPLAY INVISIBLE (-1800 1275);
FORCEADD OFFPAGE..1
(-5900 1075);
FORCEPROP 2 LAST $XR1 136 
J 0
(-6302 1075);
DISPLAY 0.638298 (-6302 1075);
PAINT MONO (-6302 1075);
FORCEPROP 2 LAST $XR0 119 
J 0
(-6182 1075);
DISPLAY 0.638298 (-6182 1075);
PAINT MONO (-6182 1075);
FORCEPROP 2 LAST PATH I52
J 0
(-5850 1150);
DISPLAY 1.021277 (-5850 1150);
PAINT ORANGE (-5850 1150);
DISPLAY INVISIBLE (-5850 1150);
FORCEPROP 2 LAST CDS_LIB mstr_standard
J 0
(-5900 1075);
PAINT ORANGE (-5900 1075);
DISPLAY INVISIBLE (-5900 1075);
FORCEPROP 1 LAST OFFPAGE TRUE
J 0
(-5575 950);
DISPLAY 0.872340 (-5575 950);
PAINT GREEN (-5575 950);
DISPLAY INVISIBLE (-5575 950);
FORCEPROP 1 LAST COMMENT_BODY TRUE
J 0
(-5775 975);
DISPLAY 0.872340 (-5775 975);
PAINT GREEN (-5775 975);
DISPLAY INVISIBLE (-5775 975);
FORCEADD GND..1
(-5025 750);
FORCEPROP 3 LASTPIN (-5025 800) SIG_NAME GND\g
J 0
(-5015 810);
DISPLAY 0.659574 (-5015 810);
PAINT MONO (-5015 810);
DISPLAY INVISIBLE (-5015 810);
FORCEPROP 1 LAST PATH I54
J 0
(-4950 750);
DISPLAY 0.872340 (-4950 750);
PAINT AQUA (-4950 750);
DISPLAY INVISIBLE (-4950 750);
FORCEPROP 2 LAST CDS_LIB mstr_symbols
J 0
(-5025 750);
PAINT ORANGE (-5025 750);
DISPLAY INVISIBLE (-5025 750);
FORCEPROP 1 LAST SIZE 1B
J 0
(-4950 700);
DISPLAY 0.872340 (-4950 700);
PAINT AQUA (-4950 700);
DISPLAY INVISIBLE (-4950 700);
FORCEPROP 1 LAST VOLTAGE 0.0V
J 0
(-5070 707);
DISPLAY 0.340426 (-5070 707);
PAINT SKYBLUE (-5070 707);
DISPLAY INVISIBLE (-5070 707);
FORCEPROP 1 LAST BODY_TYPE PLUMBING
J 0
(-5070 707);
DISPLAY 0.340426 (-5070 707);
PAINT GREEN (-5070 707);
DISPLAY INVISIBLE (-5070 707);
FORCEPROP 1 LAST HDL_POWER GND
J 0
(-5025 900);
DISPLAY 0.872340 (-5025 900);
PAINT GREEN (-5025 900);
DISPLAY INVISIBLE (-5025 900);
FORCEADD TTL1G86..1
(-2750 1025);
FORCEPROP 1 LAST VALUE 74AHCT1G86
J 0
(-2900 1175);
DISPLAY 0.617021 (-2900 1175);
PAINT SKYBLUE (-2900 1175);
FORCEPROP 2 LASTPIN (-2450 1025) $PN 4
J 0
(-2440 1035);
DISPLAY 0.617021 (-2440 1035);
PAINT MONO (-2440 1035);
FORCEPROP 2 LASTPIN (-2950 1075) $PN 1
J 2
(-2960 1085);
DISPLAY 0.617021 (-2960 1085);
PAINT MONO (-2960 1085);
FORCEPROP 1 LAST POWER_GROUP VCC=P5V_STBY;GND=GND;
J 0
(-2900 775);
DISPLAY 0.617021 (-2900 775);
PAINT ORANGE (-2900 775);
FORCEPROP 1 LAST PART_NUMBER D39848-001
J 0
(-2900 825);
DISPLAY 0.617021 (-2900 825);
PAINT BLUE (-2900 825);
FORCEPROP 2 LASTPIN (-2950 975) $PN 2
J 2
(-2960 985);
DISPLAY 0.617021 (-2960 985);
PAINT MONO (-2960 985);
FORCEPROP 1 LAST MATERIAL IC
J 0
(-2900 1225);
DISPLAY 0.617021 (-2900 1225);
PAINT SKYBLUE (-2900 1225);
FORCEPROP 1 LAST LOCATION U1L2
J 0
(-2900 1275);
DISPLAY 0.617021 (-2900 1275);
PAINT AQUA (-2900 1275);
FORCEPROP 1 LAST PATH I57
J 0
(-2675 1225);
PAINT GREEN (-2675 1225);
DISPLAY INVISIBLE (-2675 1225);
FORCEPROP 2 LAST CDS_LIB mstr_ttl
J 0
(-2750 1025);
PAINT ORANGE (-2750 1025);
DISPLAY INVISIBLE (-2750 1025);
FORCEPROP 2 LAST ROOM MIO_CHASSIS
J 0
(-2900 1325);
DISPLAY 1.021277 (-2900 1325);
PAINT ORANGE (-2900 1325);
DISPLAY INVISIBLE (-2900 1325);
FORCEPROP 2 LAST $SEC 1
J 0
(-2900 1325);
PAINT MONO (-2900 1325);
DISPLAY INVISIBLE (-2900 1325);
FORCEPROP 2 LAST CDS_SEC 1
J 0
(-2900 1325);
PAINT MONO (-2900 1325);
DISPLAY INVISIBLE (-2900 1325);
FORCEPROP 2 LAST BOM_COST MIO_CHASSIS
J 0
(-2900 1375);
DISPLAY 1.021277 (-2900 1375);
PAINT ORANGE (-2900 1375);
DISPLAY INVISIBLE (-2900 1375);
FORCEPROP 1 LAST PACK_TYPE SOTLF
J 0
(-2900 1325);
PAINT SKYBLUE (-2900 1325);
DISPLAY INVISIBLE (-2900 1325);
FORCEPROP 2 LAST CDS_LOCATION U1L2
J 0
(-2900 1275);
DISPLAY 0.617021 (-2900 1275);
PAINT AQUA (-2900 1275);
DISPLAY INVISIBLE (-2900 1275);
FORCEADD RES..2
(-1175 1350);
FORCEPROP 1 LASTPIN (-1175 1450) $PN 1
J 0
(-1170 1412);
DISPLAY 0.617021 (-1170 1412);
PAINT ORANGE (-1170 1412);
FORCEPROP 1 LAST WATTAGE 1/16W
J 0
(-1135 1325);
DISPLAY 0.617021 (-1135 1325);
PAINT SKYBLUE (-1135 1325);
FORCEPROP 1 LAST MATERIAL CHIP
J 0
(-1135 1275);
DISPLAY 0.617021 (-1135 1275);
PAINT SKYBLUE (-1135 1275);
FORCEPROP 1 LASTPIN (-1175 1250) $PN 2
J 0
(-1170 1260);
DISPLAY 0.617021 (-1170 1260);
PAINT ORANGE (-1170 1260);
FORCEPROP 1 LAST PACK_TYPE 0402
J 0
(-1135 1175);
DISPLAY 0.617021 (-1135 1175);
PAINT SKYBLUE (-1135 1175);
FORCEPROP 1 LAST PART_NUMBER G21497-024
J 0
(-1135 1225);
DISPLAY 0.617021 (-1135 1225);
PAINT BLUE (-1135 1225);
FORCEPROP 1 LAST LOCATION R1L8
J 0
(-1130 1475);
DISPLAY 0.617021 (-1130 1475);
PAINT AQUA (-1130 1475);
FORCEPROP 1 LAST VALUE 470.0
J 0
(-1130 1425);
DISPLAY 0.617021 (-1130 1425);
PAINT SKYBLUE (-1130 1425);
FORCEPROP 1 LAST TOLERANCE 5%
J 0
(-1130 1375);
DISPLAY 0.617021 (-1130 1375);
PAINT SKYBLUE (-1130 1375);
FORCEPROP 1 LAST PATH I58
J 0
(-1125 1525);
DISPLAY 0.978723 (-1125 1525);
PAINT WHITE (-1125 1525);
DISPLAY INVISIBLE (-1125 1525);
FORCEPROP 2 LAST CDS_LOCATION R1L8
J 0
(-1130 1475);
DISPLAY 0.617021 (-1130 1475);
PAINT AQUA (-1130 1475);
DISPLAY INVISIBLE (-1130 1475);
FORCEPROP 2 LAST CDS_LIB mstr_discrete
J 0
(-1175 1350);
PAINT ORANGE (-1175 1350);
DISPLAY INVISIBLE (-1175 1350);
FORCEPROP 2 LAST ROOM MIO_CHASSIS
J 0
(-1125 1525);
DISPLAY 1.021277 (-1125 1525);
PAINT ORANGE (-1125 1525);
DISPLAY INVISIBLE (-1125 1525);
FORCEPROP 0 LAST SEC 1
J 0
(-1125 1525);
DISPLAY 0.680851 (-1125 1525);
PAINT MONO (-1125 1525);
DISPLAY INVISIBLE (-1125 1525);
FORCEPROP 2 LAST BOM_COST MIO_CHASSIS
J 0
(-1125 1575);
DISPLAY 1.021277 (-1125 1575);
PAINT ORANGE (-1125 1575);
DISPLAY INVISIBLE (-1125 1575);
FORCEPROP 2 LAST SEC_TYPE 0402
J 0
(-1125 1575);
DISPLAY 1.021277 (-1125 1575);
PAINT ORANGE (-1125 1575);
DISPLAY INVISIBLE (-1125 1575);
FORCEADD P5V_STBY..1
(-1175 1700);
FORCEPROP 3 LASTPIN (-1175 1650) SIG_NAME P5V_STBY\g
J 0
(-1165 1660);
DISPLAY 0.659574 (-1165 1660);
PAINT MONO (-1165 1660);
DISPLAY INVISIBLE (-1165 1660);
FORCEPROP 1 LAST VOLTAGE 5.0V
J 0
(-1220 1657);
DISPLAY 0.340426 (-1220 1657);
PAINT SKYBLUE (-1220 1657);
DISPLAY INVISIBLE (-1220 1657);
FORCEPROP 2 LAST CDS_LIB mstr_symbols
J 0
(-1175 1700);
PAINT ORANGE (-1175 1700);
DISPLAY INVISIBLE (-1175 1700);
FORCEPROP 1 LAST SIZE 1B
J 0
(-1130 1722);
DISPLAY 0.340426 (-1130 1722);
PAINT GREEN (-1130 1722);
DISPLAY INVISIBLE (-1130 1722);
FORCEPROP 1 LAST PATH I59
J 0
(-1130 1702);
DISPLAY 0.340426 (-1130 1702);
PAINT GREEN (-1130 1702);
DISPLAY INVISIBLE (-1130 1702);
FORCEPROP 1 LAST BODY_TYPE PLUMBING
J 0
(-1220 1657);
DISPLAY 0.340426 (-1220 1657);
PAINT GREEN (-1220 1657);
DISPLAY INVISIBLE (-1220 1657);
FORCEPROP 1 LAST HDL_POWER P5V_STBY
J 0
(-1475 1575);
DISPLAY 0.872340 (-1475 1575);
PAINT ORANGE (-1475 1575);
DISPLAY INVISIBLE (-1475 1575);
FORCEADD P3V3_STBY..1
(-5925 4800);
FORCEPROP 3 LASTPIN (-5925 4750) SIG_NAME P3V3_STBY\g
J 0
(-5915 4760);
DISPLAY 0.659574 (-5915 4760);
PAINT MONO (-5915 4760);
DISPLAY INVISIBLE (-5915 4760);
FORCEPROP 1 LAST PATH I6
J 0
(-5880 4802);
DISPLAY 0.340426 (-5880 4802);
PAINT GREEN (-5880 4802);
DISPLAY INVISIBLE (-5880 4802);
FORCEPROP 1 LAST SIZE 1B
J 0
(-5880 4822);
DISPLAY 0.340426 (-5880 4822);
PAINT GREEN (-5880 4822);
DISPLAY INVISIBLE (-5880 4822);
FORCEPROP 2 LAST CDS_LIB mstr_symbols
J 0
(-5925 4800);
PAINT ORANGE (-5925 4800);
DISPLAY INVISIBLE (-5925 4800);
FORCEPROP 1 LAST VOLTAGE 3.3V
J 0
(-5970 4757);
DISPLAY 0.340426 (-5970 4757);
PAINT SKYBLUE (-5970 4757);
DISPLAY INVISIBLE (-5970 4757);
FORCEPROP 1 LAST BODY_TYPE PLUMBING
J 0
(-5970 4757);
DISPLAY 0.340426 (-5970 4757);
PAINT GREEN (-5970 4757);
DISPLAY INVISIBLE (-5970 4757);
FORCEPROP 1 LAST HDL_POWER P3V3_STBY
J 0
(-6225 4675);
DISPLAY 0.872340 (-6225 4675);
PAINT ORANGE (-6225 4675);
DISPLAY INVISIBLE (-6225 4675);
FORCEADD OFFPAGE..1
(-4075 975);
FORCEPROP 2 LAST $XR2 146 
J 0
(-4327 939);
DISPLAY 0.638298 (-4327 939);
PAINT MONO (-4327 939);
FORCEPROP 2 LAST $XR1 133 
J 0
(-4447 975);
DISPLAY 0.638298 (-4447 975);
PAINT MONO (-4447 975);
FORCEPROP 2 LAST $XR0 120 
J 0
(-4327 975);
DISPLAY 0.638298 (-4327 975);
PAINT MONO (-4327 975);
FORCEPROP 2 LAST PATH I61
J 0
(-4025 1050);
DISPLAY 1.021277 (-4025 1050);
PAINT ORANGE (-4025 1050);
DISPLAY INVISIBLE (-4025 1050);
FORCEPROP 2 LAST CDS_LIB mstr_standard
J 0
(-4075 975);
PAINT ORANGE (-4075 975);
DISPLAY INVISIBLE (-4075 975);
FORCEPROP 1 LAST OFFPAGE TRUE
J 0
(-3750 850);
DISPLAY 0.872340 (-3750 850);
PAINT GREEN (-3750 850);
DISPLAY INVISIBLE (-3750 850);
FORCEPROP 1 LAST COMMENT_BODY TRUE
J 0
(-3950 875);
DISPLAY 0.872340 (-3950 875);
PAINT GREEN (-3950 875);
DISPLAY INVISIBLE (-3950 875);
FORCEADD OFFPAGE..1
(-4075 1075);
FORCEPROP 2 LAST $XR2 248 
J 0
(-4567 1075);
DISPLAY 0.638298 (-4567 1075);
PAINT MONO (-4567 1075);
FORCEPROP 2 LAST $XR1 190 
J 0
(-4447 1075);
DISPLAY 0.638298 (-4447 1075);
PAINT MONO (-4447 1075);
FORCEPROP 2 LAST $XR0 196 
J 0
(-4327 1075);
DISPLAY 0.638298 (-4327 1075);
PAINT MONO (-4327 1075);
FORCEPROP 2 LAST PATH I62
J 0
(-4025 1150);
DISPLAY 1.021277 (-4025 1150);
PAINT ORANGE (-4025 1150);
DISPLAY INVISIBLE (-4025 1150);
FORCEPROP 2 LAST CDS_LIB mstr_standard
J 0
(-4075 1075);
PAINT ORANGE (-4075 1075);
DISPLAY INVISIBLE (-4075 1075);
FORCEPROP 1 LAST OFFPAGE TRUE
J 0
(-3750 950);
DISPLAY 0.872340 (-3750 950);
PAINT GREEN (-3750 950);
DISPLAY INVISIBLE (-3750 950);
FORCEPROP 1 LAST COMMENT_BODY TRUE
J 0
(-3950 975);
DISPLAY 0.872340 (-3950 975);
PAINT GREEN (-3950 975);
DISPLAY INVISIBLE (-3950 975);
FORCEADD RES..1
(-3525 1075);
FORCEPROP 1 LAST WATTAGE 1/16W
J 2
(-3550 925);
DISPLAY 0.617021 (-3550 925);
PAINT SKYBLUE (-3550 925);
FORCEPROP 1 LAST VALUE 0.0
J 2
(-3550 975);
DISPLAY 0.617021 (-3550 975);
PAINT SKYBLUE (-3550 975);
FORCEPROP 1 LAST PART_NUMBER G21497-005
J 0
(-3575 1175);
DISPLAY 0.617021 (-3575 1175);
PAINT BLUE (-3575 1175);
FORCEPROP 1 LAST LOCATION R1L12
J 0
(-3575 1125);
DISPLAY 0.617021 (-3575 1125);
PAINT AQUA (-3575 1125);
FORCEPROP 1 LAST TOLERANCE 5%
J 0
(-3525 975);
DISPLAY 0.617021 (-3525 975);
PAINT SKYBLUE (-3525 975);
FORCEPROP 1 LAST PACK_TYPE 0402
J 0
(-3275 925);
DISPLAY 0.617021 (-3275 925);
PAINT SKYBLUE (-3275 925);
FORCEPROP 1 LASTPIN (-3625 1075) $PN 1
J 0
(-3613 1087);
DISPLAY 0.617021 (-3613 1087);
PAINT ORANGE (-3613 1087);
FORCEPROP 1 LASTPIN (-3425 1075) $PN 2
J 0
(-3463 1087);
DISPLAY 0.617021 (-3463 1087);
PAINT ORANGE (-3463 1087);
FORCEPROP 1 LAST MATERIAL CHIP
J 0
(-3525 925);
DISPLAY 0.617021 (-3525 925);
PAINT SKYBLUE (-3525 925);
FORCEPROP 2 LAST BOM_COST MIO_CHASSIS
J 0
(-3575 1275);
DISPLAY 1.021277 (-3575 1275);
PAINT ORANGE (-3575 1275);
DISPLAY INVISIBLE (-3575 1275);
FORCEPROP 2 LAST ROOM MIO_CHASSIS
J 0
(-3575 1225);
DISPLAY 1.021277 (-3575 1225);
PAINT ORANGE (-3575 1225);
DISPLAY INVISIBLE (-3575 1225);
FORCEPROP 1 LAST PATH I63
J 0
(-3575 1225);
DISPLAY 0.978723 (-3575 1225);
PAINT WHITE (-3575 1225);
DISPLAY INVISIBLE (-3575 1225);
FORCEPROP 2 LAST SEC 1
J 0
(-3575 1275);
PAINT MONO (-3575 1275);
DISPLAY INVISIBLE (-3575 1275);
FORCEPROP 2 LAST SEC_TYPE 0402
J 0
(-3575 1275);
DISPLAY 1.021277 (-3575 1275);
PAINT ORANGE (-3575 1275);
DISPLAY INVISIBLE (-3575 1275);
FORCEPROP 2 LAST CDS_LIB mstr_discrete
J 0
(-3525 1075);
PAINT ORANGE (-3525 1075);
DISPLAY INVISIBLE (-3525 1075);
FORCEPROP 2 LAST CDS_LOCATION R1L12
J 0
(-3575 1125);
DISPLAY 0.617021 (-3575 1125);
PAINT AQUA (-3575 1125);
DISPLAY INVISIBLE (-3575 1125);
FORCEADD CAP_A..1
(-2900 1725);
FORCEPROP 1 LAST TOLERANCE 10%
J 0
(-2850 1675);
DISPLAY 0.617021 (-2850 1675);
PAINT SKYBLUE (-2850 1675);
FORCEPROP 1 LASTPIN (-2900 1625) $PN 2
J 0
(-2890 1605);
DISPLAY 0.617021 (-2890 1605);
PAINT ORANGE (-2890 1605);
FORCEPROP 1 LAST MATERIAL X7R
J 0
(-2850 1625);
DISPLAY 0.617021 (-2850 1625);
PAINT SKYBLUE (-2850 1625);
FORCEPROP 1 LAST PACK_TYPE 0402V
J 0
(-2850 1525);
DISPLAY 0.617021 (-2850 1525);
PAINT SKYBLUE (-2850 1525);
FORCEPROP 1 LAST VOLTAGE 16V
J 0
(-2850 1725);
DISPLAY 0.617021 (-2850 1725);
PAINT SKYBLUE (-2850 1725);
FORCEPROP 1 LASTPIN (-2900 1825) $PN 1
J 0
(-2890 1805);
DISPLAY 0.617021 (-2890 1805);
PAINT ORANGE (-2890 1805);
FORCEPROP 1 LAST LOCATION C1L4
J 0
(-2850 1825);
DISPLAY 0.617021 (-2850 1825);
PAINT AQUA (-2850 1825);
FORCEPROP 1 LAST PART_NUMBER A36096-030
J 0
(-2850 1575);
DISPLAY 0.617021 (-2850 1575);
PAINT BLUE (-2850 1575);
FORCEPROP 1 LAST VALUE 0.1UF
J 0
(-2850 1775);
DISPLAY 0.617021 (-2850 1775);
PAINT SKYBLUE (-2850 1775);
FORCEPROP 2 LAST SEC_TYPE 0402V
J 0
(-2850 1925);
DISPLAY 1.021277 (-2850 1925);
PAINT ORANGE (-2850 1925);
DISPLAY INVISIBLE (-2850 1925);
FORCEPROP 2 LAST BOM_COST MIO_CHASSIS
J 0
(-2850 1925);
DISPLAY 1.021277 (-2850 1925);
PAINT ORANGE (-2850 1925);
DISPLAY INVISIBLE (-2850 1925);
FORCEPROP 2 LAST CDS_LOCATION C1L4
J 0
(-2850 1825);
DISPLAY 0.617021 (-2850 1825);
PAINT AQUA (-2850 1825);
DISPLAY INVISIBLE (-2850 1825);
FORCEPROP 2 LAST SEC 1
J 0
(-2850 1875);
DISPLAY 0.680851 (-2850 1875);
PAINT MONO (-2850 1875);
DISPLAY INVISIBLE (-2850 1875);
FORCEPROP 2 LAST ROOM MIO_CHASSIS
J 0
(-2850 1875);
DISPLAY 1.021277 (-2850 1875);
PAINT ORANGE (-2850 1875);
DISPLAY INVISIBLE (-2850 1875);
FORCEPROP 1 LAST PATH I64
J 0
(-2850 1875);
DISPLAY 0.978723 (-2850 1875);
PAINT WHITE (-2850 1875);
DISPLAY INVISIBLE (-2850 1875);
FORCEPROP 2 LAST CDS_SEC 1
J 0
(-2850 1875);
PAINT ORANGE (-2850 1875);
DISPLAY INVISIBLE (-2850 1875);
FORCEPROP 2 LAST CDS_LIB dev_discrete
J 0
(-2900 1725);
PAINT ORANGE (-2900 1725);
DISPLAY INVISIBLE (-2900 1725);
FORCEADD GND..1
(-2900 1475);
FORCEPROP 3 LASTPIN (-2900 1525) SIG_NAME GND\g
J 0
(-2890 1535);
DISPLAY 0.659574 (-2890 1535);
PAINT MONO (-2890 1535);
DISPLAY INVISIBLE (-2890 1535);
FORCEPROP 1 LAST PATH I66
J 0
(-2825 1475);
DISPLAY 0.872340 (-2825 1475);
PAINT AQUA (-2825 1475);
DISPLAY INVISIBLE (-2825 1475);
FORCEPROP 1 LAST SIZE 1B
J 0
(-2825 1425);
DISPLAY 0.872340 (-2825 1425);
PAINT AQUA (-2825 1425);
DISPLAY INVISIBLE (-2825 1425);
FORCEPROP 2 LAST CDS_LIB mstr_symbols
J 0
(-2900 1475);
PAINT ORANGE (-2900 1475);
DISPLAY INVISIBLE (-2900 1475);
FORCEPROP 1 LAST VOLTAGE 0.0V
J 0
(-2945 1432);
DISPLAY 0.340426 (-2945 1432);
PAINT SKYBLUE (-2945 1432);
DISPLAY INVISIBLE (-2945 1432);
FORCEPROP 1 LAST BODY_TYPE PLUMBING
J 0
(-2945 1432);
DISPLAY 0.340426 (-2945 1432);
PAINT GREEN (-2945 1432);
DISPLAY INVISIBLE (-2945 1432);
FORCEPROP 1 LAST HDL_POWER GND
J 0
(-2900 1625);
DISPLAY 0.872340 (-2900 1625);
PAINT GREEN (-2900 1625);
DISPLAY INVISIBLE (-2900 1625);
FORCEADD LED..3
(-4600 1550);
FORCEPROP 1 LAST LOCATION DS9A3
J 0
(-4700 1750);
DISPLAY 0.617021 (-4700 1750);
PAINT AQUA (-4700 1750);
FORCEPROP 2 LASTPIN (-4700 1550) $PN 1
J 2
(-4710 1560);
DISPLAY 0.617021 (-4710 1560);
PAINT ORANGE (-4710 1560);
FORCEPROP 1 LAST MATERIAL IC
J 0
(-4700 1700);
DISPLAY 0.617021 (-4700 1700);
PAINT SKYBLUE (-4700 1700);
FORCEPROP 2 LASTPIN (-4500 1550) $PN 2
J 0
(-4490 1560);
DISPLAY 0.617021 (-4490 1560);
PAINT ORANGE (-4490 1560);
FORCEPROP 1 LAST PART_NUMBER C96565-003
J 0
(-4700 1400);
DISPLAY 0.617021 (-4700 1400);
PAINT BLUE (-4700 1400);
FORCEPROP 1 LAST COLOR YELLOW
J 0
(-4700 1650);
DISPLAY 0.617021 (-4700 1650);
PAINT BLUE (-4700 1650);
FORCEPROP 2 LAST CDS_LIB mstr_discrete
J 0
(-4600 1550);
PAINT MONO (-4600 1550);
DISPLAY INVISIBLE (-4600 1550);
FORCEPROP 1 LAST PATH I67
J 0
(-4250 1700);
DISPLAY 0.978723 (-4250 1700);
PAINT BLUE (-4250 1700);
DISPLAY INVISIBLE (-4250 1700);
FORCEPROP 1 LAST PACK_TYPE 1NCLF
J 0
(-4700 1800);
DISPLAY 0.978723 (-4700 1800);
PAINT SKYBLUE (-4700 1800);
DISPLAY INVISIBLE (-4700 1800);
FORCEPROP 2 LAST SEC_TYPE 1NCLF
J 0
(-4700 1800);
DISPLAY 1.021277 (-4700 1800);
PAINT ORANGE (-4700 1800);
DISPLAY INVISIBLE (-4700 1800);
FORCEPROP 2 LAST BOM_COST MIO_CHASSIS
J 0
(-4700 1850);
DISPLAY 1.021277 (-4700 1850);
PAINT ORANGE (-4700 1850);
DISPLAY INVISIBLE (-4700 1850);
FORCEPROP 2 LAST SEC 1
J 0
(-4700 1800);
DISPLAY 0.680851 (-4700 1800);
PAINT MONO (-4700 1800);
DISPLAY INVISIBLE (-4700 1800);
FORCEPROP 2 LAST CDS_LOCATION DS9A3
J 0
(-4700 1750);
DISPLAY 0.617021 (-4700 1750);
PAINT AQUA (-4700 1750);
DISPLAY INVISIBLE (-4700 1750);
FORCEPROP 2 LAST ROOM MIO_CHASSIS
J 0
(-4700 1800);
DISPLAY 1.021277 (-4700 1800);
PAINT ORANGE (-4700 1800);
DISPLAY INVISIBLE (-4700 1800);
FORCEADD P3V3_STBY..1
(-575 3800);
FORCEPROP 3 LASTPIN (-575 3750) SIG_NAME P3V3_STBY\g
J 0
(-565 3760);
DISPLAY 0.659574 (-565 3760);
PAINT MONO (-565 3760);
DISPLAY INVISIBLE (-565 3760);
FORCEPROP 2 LAST CDS_LIB mstr_symbols
J 0
(-575 3800);
PAINT ORANGE (-575 3800);
DISPLAY INVISIBLE (-575 3800);
FORCEPROP 1 LAST VOLTAGE 3.3V
J 0
(-620 3757);
DISPLAY 0.340426 (-620 3757);
PAINT SKYBLUE (-620 3757);
DISPLAY INVISIBLE (-620 3757);
FORCEPROP 1 LAST SIZE 1B
J 0
(-530 3822);
DISPLAY 0.340426 (-530 3822);
PAINT GREEN (-530 3822);
DISPLAY INVISIBLE (-530 3822);
FORCEPROP 1 LAST PATH I70
J 0
(-530 3802);
DISPLAY 0.340426 (-530 3802);
PAINT GREEN (-530 3802);
DISPLAY INVISIBLE (-530 3802);
FORCEPROP 1 LAST BODY_TYPE PLUMBING
J 0
(-620 3757);
DISPLAY 0.340426 (-620 3757);
PAINT GREEN (-620 3757);
DISPLAY INVISIBLE (-620 3757);
FORCEPROP 1 LAST HDL_POWER P3V3_STBY
J 0
(-875 3675);
DISPLAY 0.872340 (-875 3675);
PAINT ORANGE (-875 3675);
DISPLAY INVISIBLE (-875 3675);
FORCEADD GND..1
(-575 3200);
FORCEPROP 3 LASTPIN (-575 3250) SIG_NAME GND\g
J 0
(-565 3260);
DISPLAY 0.659574 (-565 3260);
PAINT MONO (-565 3260);
DISPLAY INVISIBLE (-565 3260);
FORCEPROP 1 LAST SIZE 1B
J 0
(-500 3150);
DISPLAY 0.872340 (-500 3150);
PAINT AQUA (-500 3150);
DISPLAY INVISIBLE (-500 3150);
FORCEPROP 1 LAST PATH I71
J 0
(-500 3200);
DISPLAY 0.872340 (-500 3200);
PAINT AQUA (-500 3200);
DISPLAY INVISIBLE (-500 3200);
FORCEPROP 1 LAST VOLTAGE 0.0V
J 0
(-620 3157);
DISPLAY 0.340426 (-620 3157);
PAINT SKYBLUE (-620 3157);
DISPLAY INVISIBLE (-620 3157);
FORCEPROP 2 LAST CDS_LIB mstr_symbols
J 0
(-575 3200);
PAINT ORANGE (-575 3200);
DISPLAY INVISIBLE (-575 3200);
FORCEPROP 1 LAST BODY_TYPE PLUMBING
J 0
(-620 3157);
DISPLAY 0.340426 (-620 3157);
PAINT GREEN (-620 3157);
DISPLAY INVISIBLE (-620 3157);
FORCEPROP 1 LAST HDL_POWER GND
J 0
(-575 3350);
DISPLAY 0.872340 (-575 3350);
PAINT GREEN (-575 3350);
DISPLAY INVISIBLE (-575 3350);
FORCEADD SWITCH_D37771002..1
R 3
(-7075 2675);
FORCEPROP 1 LASTPIN (-6975 2575) $PN 2
R 1
J 0
(-7200 2515);
DISPLAY 0.617021 (-7200 2515);
PAINT WHITE (-7200 2515);
FORCEPROP 1 LASTPIN (-7225 2775) $PN 3
R 1
J 2
(-6975 2820);
DISPLAY 0.617021 (-6975 2820);
PAINT WHITE (-6975 2820);
FORCEPROP 1 LASTPIN (-7225 2575) $PN 4
R 1
J 0
(-6975 2510);
DISPLAY 0.617021 (-6975 2510);
PAINT WHITE (-6975 2510);
FORCEPROP 1 LAST LOCATION S9A1
R 1
J 2
(-7155 2470);
DISPLAY 0.617021 (-7155 2470);
PAINT AQUA (-7155 2470);
FORCEPROP 1 LAST MATERIAL IC
R 1
J 2
(-7105 2470);
DISPLAY 0.617021 (-7105 2470);
PAINT SKYBLUE (-7105 2470);
FORCEPROP 1 LAST PART_NUMBER D37771-002
R 1
J 2
(-7050 2470);
DISPLAY 0.617021 (-7050 2470);
PAINT BLUE (-7050 2470);
FORCEPROP 1 LASTPIN (-6975 2775) $PN 1
R 1
J 2
(-7200 2820);
DISPLAY 0.617021 (-7200 2820);
PAINT WHITE (-7200 2820);
FORCEPROP 2 LAST CDS_LOCATION S9A1
R 1
J 2
(-7155 2470);
DISPLAY 0.617021 (-7155 2470);
PAINT AQUA (-7155 2470);
DISPLAY INVISIBLE (-7155 2470);
FORCEPROP 2 LAST CDS_LIB mstr_misc
R 1
J 2
(-7075 2675);
PAINT MONO (-7075 2675);
DISPLAY INVISIBLE (-7075 2675);
FORCEPROP 1 LAST CDS_LMAN_SYM_OUTLINE -100,125,100,-75
R 1
J 2
(-7075 2675);
DISPLAY 0.468085 (-7075 2675);
PAINT GREEN (-7075 2675);
DISPLAY INVISIBLE (-7075 2675);
FORCEPROP 2 LAST SEC 1
R 1
J 2
(-7225 2450);
DISPLAY 0.680851 (-7225 2450);
PAINT MONO (-7225 2450);
DISPLAY INVISIBLE (-7225 2450);
FORCEPROP 2 LAST SEC_TYPE SM
R 1
J 2
(-7225 2450);
DISPLAY 1.021277 (-7225 2450);
PAINT ORANGE (-7225 2450);
DISPLAY INVISIBLE (-7225 2450);
FORCEPROP 1 LAST PATH I78
R 1
J 2
(-7100 1975);
PAINT WHITE (-7100 1975);
DISPLAY INVISIBLE (-7100 1975);
FORCEPROP 1 LAST PACK_TYPE SM
R 1
J 2
(-7205 2470);
PAINT SKYBLUE (-7205 2470);
DISPLAY INVISIBLE (-7205 2470);
FORCEPROP 0 LAST ROOM MIO_CHASSIS
R 1
J 0
(-6975 2850);
DISPLAY 1.021277 (-6975 2850);
PAINT ORANGE (-6975 2850);
DISPLAY INVISIBLE (-6975 2850);
FORCEPROP 0 LAST BOM_COST MIO_CHASSIS
R 1
J 0
(-7000 2900);
DISPLAY 1.021277 (-7000 2900);
PAINT ORANGE (-7000 2900);
DISPLAY INVISIBLE (-7000 2900);
FORCEADD P3V3_STBY..1
(-3700 1825);
FORCEPROP 3 LASTPIN (-3700 1775) SIG_NAME P3V3_STBY\g
J 0
(-3690 1785);
DISPLAY 0.659574 (-3690 1785);
PAINT MONO (-3690 1785);
DISPLAY INVISIBLE (-3690 1785);
FORCEPROP 1 LAST SIZE 1B
J 0
(-3655 1847);
DISPLAY 0.340426 (-3655 1847);
PAINT GREEN (-3655 1847);
DISPLAY INVISIBLE (-3655 1847);
FORCEPROP 1 LAST PATH I85
J 0
(-3655 1827);
DISPLAY 0.340426 (-3655 1827);
PAINT GREEN (-3655 1827);
DISPLAY INVISIBLE (-3655 1827);
FORCEPROP 2 LAST CDS_LIB mstr_symbols
J 0
(-3700 1825);
PAINT MONO (-3700 1825);
DISPLAY INVISIBLE (-3700 1825);
FORCEPROP 1 LAST VOLTAGE 3.3V
J 0
(-3745 1782);
DISPLAY 0.340426 (-3745 1782);
PAINT SKYBLUE (-3745 1782);
DISPLAY INVISIBLE (-3745 1782);
FORCEPROP 1 LAST BODY_TYPE PLUMBING
J 0
(-3745 1782);
DISPLAY 0.340426 (-3745 1782);
PAINT GREEN (-3745 1782);
DISPLAY INVISIBLE (-3745 1782);
FORCEPROP 1 LAST HDL_POWER P3V3_STBY
J 0
(-4000 1700);
DISPLAY 0.872340 (-4000 1700);
PAINT ORANGE (-4000 1700);
DISPLAY INVISIBLE (-4000 1700);
FORCEADD P5V_STBY..1
(-2900 1975);
FORCEPROP 3 LASTPIN (-2900 1925) SIG_NAME P5V_STBY\g
J 0
(-2890 1935);
DISPLAY 0.659574 (-2890 1935);
PAINT MONO (-2890 1935);
DISPLAY INVISIBLE (-2890 1935);
FORCEPROP 1 LAST PATH I86
J 0
(-2855 1977);
DISPLAY 0.340426 (-2855 1977);
PAINT GREEN (-2855 1977);
DISPLAY INVISIBLE (-2855 1977);
FORCEPROP 1 LAST SIZE 1B
J 0
(-2855 1997);
DISPLAY 0.340426 (-2855 1997);
PAINT GREEN (-2855 1997);
DISPLAY INVISIBLE (-2855 1997);
FORCEPROP 2 LAST CDS_LIB mstr_symbols
J 0
(-2900 1975);
PAINT MONO (-2900 1975);
DISPLAY INVISIBLE (-2900 1975);
FORCEPROP 1 LAST VOLTAGE 5.0V
J 0
(-2945 1932);
DISPLAY 0.340426 (-2945 1932);
PAINT SKYBLUE (-2945 1932);
DISPLAY INVISIBLE (-2945 1932);
FORCEPROP 1 LAST BODY_TYPE PLUMBING
J 0
(-2945 1932);
DISPLAY 0.340426 (-2945 1932);
PAINT GREEN (-2945 1932);
DISPLAY INVISIBLE (-2945 1932);
FORCEPROP 1 LAST HDL_POWER P5V_STBY
J 0
(-3200 1850);
DISPLAY 0.872340 (-3200 1850);
PAINT ORANGE (-3200 1850);
DISPLAY INVISIBLE (-3200 1850);
FORCEADD OFFPAGE..1
(-7325 3525);
FORCEPROP 2 LAST $XR0 247 
J 0
(-7607 3525);
DISPLAY 0.638298 (-7607 3525);
PAINT MONO (-7607 3525);
FORCEPROP 2 LAST PATH I87
J 0
(-7575 3575);
DISPLAY 1.021277 (-7575 3575);
PAINT ORANGE (-7575 3575);
DISPLAY INVISIBLE (-7575 3575);
FORCEPROP 2 LAST CDS_LIB mstr_standard
J 0
(-7325 3525);
PAINT ORANGE (-7325 3525);
DISPLAY INVISIBLE (-7325 3525);
FORCEPROP 1 LAST OFFPAGE TRUE
J 0
(-7000 3400);
DISPLAY 0.872340 (-7000 3400);
PAINT GREEN (-7000 3400);
DISPLAY INVISIBLE (-7000 3400);
FORCEPROP 1 LAST COMMENT_BODY TRUE
J 0
(-7200 3425);
DISPLAY 0.872340 (-7200 3425);
PAINT GREEN (-7200 3425);
DISPLAY INVISIBLE (-7200 3425);
FORCEADD SWITCH_D37771002..1
R 2
(-7200 4150);
FORCEPROP 1 LAST MATERIAL IC
J 2
(-7405 4180);
DISPLAY 0.617021 (-7405 4180);
PAINT SKYBLUE (-7405 4180);
FORCEPROP 1 LASTPIN (-7100 4300) $PN 3
J 2
(-7055 4050);
PAINT WHITE (-7055 4050);
FORCEPROP 1 LASTPIN (-7300 4300) $PN 4
J 0
(-7365 4050);
PAINT WHITE (-7365 4050);
FORCEPROP 1 LAST PART_NUMBER D37771-002
J 2
(-7405 4125);
DISPLAY 0.617021 (-7405 4125);
PAINT BLUE (-7405 4125);
FORCEPROP 1 LAST LOCATION S9A2
J 2
(-7405 4230);
DISPLAY 0.617021 (-7405 4230);
PAINT AQUA (-7405 4230);
FORCEPROP 1 LASTPIN (-7300 4050) $PN 2
J 0
(-7385 4225);
PAINT WHITE (-7385 4225);
FORCEPROP 1 LASTPIN (-7100 4050) $PN 1
J 2
(-7030 4225);
PAINT WHITE (-7030 4225);
FORCEPROP 1 LAST PACK_TYPE SM
J 2
(-7405 4280);
PAINT SKYBLUE (-7405 4280);
DISPLAY INVISIBLE (-7405 4280);
FORCEPROP 2 LAST SEC 1
J 0
(-7400 4275);
DISPLAY 0.680851 (-7400 4275);
PAINT MONO (-7400 4275);
DISPLAY INVISIBLE (-7400 4275);
FORCEPROP 2 LAST SEC_TYPE SM
J 0
(-7400 4275);
DISPLAY 1.021277 (-7400 4275);
PAINT ORANGE (-7400 4275);
DISPLAY INVISIBLE (-7400 4275);
FORCEPROP 2 LAST CDS_LIB mstr_misc
R 3
J 0
(-7200 4150);
PAINT MONO (-7200 4150);
DISPLAY INVISIBLE (-7200 4150);
FORCEPROP 1 LAST PATH I92
J 2
(-7900 4175);
PAINT WHITE (-7900 4175);
DISPLAY INVISIBLE (-7900 4175);
FORCEPROP 1 LAST CDS_LMAN_SYM_OUTLINE -100,125,100,-75
J 2
(-7200 4150);
DISPLAY 0.468085 (-7200 4150);
PAINT GREEN (-7200 4150);
DISPLAY INVISIBLE (-7200 4150);
FORCEPROP 0 LAST BOM_COST MIO_CHASSIS
J 0
(-6975 4075);
DISPLAY 1.021277 (-6975 4075);
PAINT ORANGE (-6975 4075);
DISPLAY INVISIBLE (-6975 4075);
FORCEPROP 0 LAST ROOM MIO_CHASSIS
J 0
(-7025 4050);
DISPLAY 1.021277 (-7025 4050);
PAINT ORANGE (-7025 4050);
DISPLAY INVISIBLE (-7025 4050);
FORCEADD TC7PZ14FU-GP..1
(-3725 2725);
FORCEPROP 2 LASTPIN (-3375 2775) $PN 6
J 0
(-3365 2785);
DISPLAY 0.808511 (-3365 2785);
PAINT ORANGE (-3365 2785);
FORCEPROP 2 LASTPIN (-3375 2725) $PN 5
J 0
(-3365 2735);
DISPLAY 0.808511 (-3365 2735);
PAINT ORANGE (-3365 2735);
FORCEPROP 2 LASTPIN (-3375 2675) $PN 4
J 0
(-3365 2685);
DISPLAY 0.808511 (-3365 2685);
PAINT ORANGE (-3365 2685);
FORCEPROP 1 LAST LOCATION U9A3
J 0
(-3925 2900);
DISPLAY 0.617021 (-3925 2900);
PAINT GREEN (-3925 2900);
FORCEPROP 1 LAST VALUE TC7PZ14FU-GP
J 0
(-3925 2525);
DISPLAY 0.617021 (-3925 2525);
PAINT GREEN (-3925 2525);
FORCEPROP 2 LASTPIN (-4075 2775) $PN 1
J 2
(-4085 2785);
DISPLAY 0.808511 (-4085 2785);
PAINT ORANGE (-4085 2785);
FORCEPROP 2 LASTPIN (-4075 2725) $PN 2
J 2
(-4085 2735);
DISPLAY 0.808511 (-4085 2735);
PAINT ORANGE (-4085 2735);
FORCEPROP 2 LASTPIN (-4075 2675) $PN 3
J 2
(-4085 2685);
DISPLAY 0.808511 (-4085 2685);
PAINT ORANGE (-4085 2685);
FORCEPROP 2 LAST CDS_LIB w_hdl
J 0
(-3725 2725);
PAINT MONO (-3725 2725);
DISPLAY INVISIBLE (-3725 2725);
FORCEPROP 1 LAST CDS_LMAN_SYM_OUTLINE -200,150,200,-150
J 0
(-3725 2725);
DISPLAY 0.468085 (-3725 2725);
PAINT GREEN (-3725 2725);
DISPLAY INVISIBLE (-3725 2725);
FORCEPROP 2 LAST SEC 1
J 0
(-3925 2950);
DISPLAY 0.680851 (-3925 2950);
PAINT MONO (-3925 2950);
DISPLAY INVISIBLE (-3925 2950);
FORCEPROP 2 LAST SEC_TYPE DISCRET-GA1
J 0
(-3925 2950);
DISPLAY 1.021277 (-3925 2950);
PAINT ORANGE (-3925 2950);
DISPLAY INVISIBLE (-3925 2950);
FORCEPROP 1 LAST PATH I93
J 0
(-3725 2725);
DISPLAY 0.617021 (-3725 2725);
PAINT GREEN (-3725 2725);
DISPLAY INVISIBLE (-3725 2725);
FORCEPROP 1 LAST PACK_TYPE DISCRET-GA1
J 0
(-3725 2725);
DISPLAY 0.617021 (-3725 2725);
PAINT GREEN (-3725 2725);
DISPLAY INVISIBLE (-3725 2725);
FORCEPROP 1 LAST PART_NUMBER 073.7PZ14.0007
J 0
(-3725 2725);
DISPLAY 0.617021 (-3725 2725);
PAINT GREEN (-3725 2725);
DISPLAY INVISIBLE (-3725 2725);
FORCEADD OFFPAGE..2
(-1450 2675);
FORCEPROP 2 LAST $XR1 145 
J 0
(-1141 2675);
DISPLAY 0.638298 (-1141 2675);
PAINT MONO (-1141 2675);
FORCEPROP 2 LAST $XR0 119 
J 0
(-1261 2675);
DISPLAY 0.638298 (-1261 2675);
PAINT MONO (-1261 2675);
FORCEPROP 2 LAST PATH I94
J 0
(-1125 2725);
DISPLAY 1.021277 (-1125 2725);
PAINT ORANGE (-1125 2725);
DISPLAY INVISIBLE (-1125 2725);
FORCEPROP 2 LAST CDS_LIB mstr_standard
J 0
(-1450 2675);
PAINT ORANGE (-1450 2675);
DISPLAY INVISIBLE (-1450 2675);
FORCEPROP 1 LAST OFFPAGE TRUE
J 0
(-1125 2550);
DISPLAY 0.872340 (-1125 2550);
PAINT GREEN (-1125 2550);
DISPLAY INVISIBLE (-1125 2550);
FORCEPROP 1 LAST COMMENT_BODY TRUE
J 0
(-1495 2580);
DISPLAY 0.872340 (-1495 2580);
PAINT GREEN (-1495 2580);
DISPLAY INVISIBLE (-1495 2580);
FORCEADD RES..1
(-2225 2675);
FORCEPROP 1 LASTPIN (-2325 2675) $PN 1
J 0
(-2313 2687);
DISPLAY 0.617021 (-2313 2687);
PAINT ORANGE (-2313 2687);
FORCEPROP 1 LAST PART_NUMBER G21796-017
J 0
(-2275 2775);
DISPLAY 0.617021 (-2275 2775);
PAINT BLUE (-2275 2775);
FORCEPROP 1 LAST LOCATION R9A9
J 0
(-2275 2725);
DISPLAY 0.617021 (-2275 2725);
PAINT AQUA (-2275 2725);
FORCEPROP 1 LASTPIN (-2125 2675) $PN 2
J 0
(-2163 2687);
DISPLAY 0.617021 (-2163 2687);
PAINT ORANGE (-2163 2687);
FORCEPROP 1 LAST TOLERANCE 1%
J 0
(-2225 2575);
DISPLAY 0.617021 (-2225 2575);
PAINT SKYBLUE (-2225 2575);
FORCEPROP 1 LAST VALUE 100.0
J 2
(-2250 2575);
DISPLAY 0.617021 (-2250 2575);
PAINT SKYBLUE (-2250 2575);
FORCEPROP 1 LAST WATTAGE 1/16W
J 2
(-2250 2525);
DISPLAY 0.617021 (-2250 2525);
PAINT SKYBLUE (-2250 2525);
FORCEPROP 1 LAST MATERIAL CHIP
J 0
(-2225 2525);
DISPLAY 0.617021 (-2225 2525);
PAINT SKYBLUE (-2225 2525);
FORCEPROP 1 LAST PACK_TYPE 0402
J 0
(-2075 2575);
DISPLAY 0.617021 (-2075 2575);
PAINT SKYBLUE (-2075 2575);
FORCEPROP 2 LAST CDS_LIB mstr_discrete
J 0
(-2225 2675);
PAINT ORANGE (-2225 2675);
DISPLAY INVISIBLE (-2225 2675);
FORCEPROP 2 LAST SEC_TYPE 0402
J 0
(-2275 2875);
DISPLAY 1.021277 (-2275 2875);
PAINT ORANGE (-2275 2875);
DISPLAY INVISIBLE (-2275 2875);
FORCEPROP 2 LAST BOM_COST MIO_CHASSIS
J 0
(-2275 2875);
DISPLAY 1.021277 (-2275 2875);
PAINT ORANGE (-2275 2875);
DISPLAY INVISIBLE (-2275 2875);
FORCEPROP 0 LAST SEC 1
J 0
(-2275 2825);
DISPLAY 0.680851 (-2275 2825);
PAINT MONO (-2275 2825);
DISPLAY INVISIBLE (-2275 2825);
FORCEPROP 2 LAST CDS_LOCATION R9A9
J 0
(-2275 2725);
DISPLAY 0.617021 (-2275 2725);
PAINT AQUA (-2275 2725);
DISPLAY INVISIBLE (-2275 2725);
FORCEPROP 2 LAST ROOM MIO_CHASSIS
J 0
(-2275 2825);
DISPLAY 1.021277 (-2275 2825);
PAINT ORANGE (-2275 2825);
DISPLAY INVISIBLE (-2275 2825);
FORCEPROP 0 LAST CDS_SEC 1
J 0
(-2275 2825);
PAINT MONO (-2275 2825);
DISPLAY INVISIBLE (-2275 2825);
FORCEPROP 1 LAST PATH I95
J 0
(-2275 2825);
DISPLAY 0.978723 (-2275 2825);
PAINT WHITE (-2275 2825);
DISPLAY INVISIBLE (-2275 2825);
FORCEADD GND..1
(-4200 2475);
FORCEPROP 3 LASTPIN (-4200 2525) SIG_NAME GND\g
J 0
(-4190 2535);
DISPLAY 0.659574 (-4190 2535);
PAINT MONO (-4190 2535);
DISPLAY INVISIBLE (-4190 2535);
FORCEPROP 2 LAST CDS_LIB mstr_symbols
J 0
(-4200 2475);
PAINT MONO (-4200 2475);
DISPLAY INVISIBLE (-4200 2475);
FORCEPROP 1 LAST PATH I96
J 0
(-4125 2475);
DISPLAY 0.872340 (-4125 2475);
PAINT AQUA (-4125 2475);
DISPLAY INVISIBLE (-4125 2475);
FORCEPROP 1 LAST SIZE 1B
J 0
(-4125 2425);
DISPLAY 0.872340 (-4125 2425);
PAINT AQUA (-4125 2425);
DISPLAY INVISIBLE (-4125 2425);
FORCEPROP 1 LAST VOLTAGE 0.0V
J 0
(-4245 2432);
DISPLAY 0.340426 (-4245 2432);
PAINT SKYBLUE (-4245 2432);
DISPLAY INVISIBLE (-4245 2432);
FORCEPROP 1 LAST BODY_TYPE PLUMBING
J 0
(-4245 2432);
DISPLAY 0.340426 (-4245 2432);
PAINT GREEN (-4245 2432);
DISPLAY INVISIBLE (-4245 2432);
FORCEPROP 1 LAST HDL_POWER GND
J 0
(-4200 2625);
DISPLAY 0.872340 (-4200 2625);
PAINT GREEN (-4200 2625);
DISPLAY INVISIBLE (-4200 2625);
FORCEADD TC7PZ14FU-GP..1
(-3675 4125);
FORCEPROP 1 LAST VALUE TC7PZ14FU-GP
J 0
(-3875 3925);
DISPLAY 0.617021 (-3875 3925);
PAINT GREEN (-3875 3925);
FORCEPROP 2 LASTPIN (-4025 4175) $PN 1
J 2
(-4035 4185);
DISPLAY 0.808511 (-4035 4185);
PAINT ORANGE (-4035 4185);
FORCEPROP 2 LASTPIN (-4025 4125) $PN 2
J 2
(-4035 4135);
DISPLAY 0.808511 (-4035 4135);
PAINT ORANGE (-4035 4135);
FORCEPROP 2 LASTPIN (-4025 4075) $PN 3
J 2
(-4035 4085);
DISPLAY 0.808511 (-4035 4085);
PAINT ORANGE (-4035 4085);
FORCEPROP 1 LAST LOCATION U9A4
J 0
(-3875 4300);
DISPLAY 0.617021 (-3875 4300);
PAINT GREEN (-3875 4300);
FORCEPROP 2 LASTPIN (-3325 4075) $PN 4
J 0
(-3315 4085);
DISPLAY 0.808511 (-3315 4085);
PAINT ORANGE (-3315 4085);
FORCEPROP 2 LASTPIN (-3325 4125) $PN 5
J 0
(-3315 4135);
DISPLAY 0.808511 (-3315 4135);
PAINT ORANGE (-3315 4135);
FORCEPROP 2 LASTPIN (-3325 4175) $PN 6
J 0
(-3315 4185);
DISPLAY 0.808511 (-3315 4185);
PAINT ORANGE (-3315 4185);
FORCEPROP 1 LAST PART_NUMBER 073.7PZ14.0007
J 0
(-3675 4125);
DISPLAY 0.617021 (-3675 4125);
PAINT GREEN (-3675 4125);
DISPLAY INVISIBLE (-3675 4125);
FORCEPROP 1 LAST CDS_LMAN_SYM_OUTLINE -200,150,200,-150
J 0
(-3675 4125);
DISPLAY 0.468085 (-3675 4125);
PAINT GREEN (-3675 4125);
DISPLAY INVISIBLE (-3675 4125);
FORCEPROP 1 LAST PATH I97
J 0
(-3675 4125);
DISPLAY 0.617021 (-3675 4125);
PAINT GREEN (-3675 4125);
DISPLAY INVISIBLE (-3675 4125);
FORCEPROP 2 LAST CDS_LIB w_hdl
J 0
(-3675 4125);
PAINT MONO (-3675 4125);
DISPLAY INVISIBLE (-3675 4125);
FORCEPROP 2 LAST SEC_TYPE DISCRET-GA1
J 0
(-3875 4350);
DISPLAY 1.021277 (-3875 4350);
PAINT ORANGE (-3875 4350);
DISPLAY INVISIBLE (-3875 4350);
FORCEPROP 2 LAST SEC 1
J 0
(-3875 4350);
DISPLAY 0.680851 (-3875 4350);
PAINT MONO (-3875 4350);
DISPLAY INVISIBLE (-3875 4350);
FORCEPROP 1 LAST PACK_TYPE DISCRET-GA1
J 0
(-3675 4125);
DISPLAY 0.617021 (-3675 4125);
PAINT GREEN (-3675 4125);
DISPLAY INVISIBLE (-3675 4125);
FORCEADD GND..1
(-4150 3875);
FORCEPROP 3 LASTPIN (-4150 3925) SIG_NAME GND\g
J 0
(-4140 3935);
DISPLAY 0.659574 (-4140 3935);
PAINT MONO (-4140 3935);
DISPLAY INVISIBLE (-4140 3935);
FORCEPROP 1 LAST VOLTAGE 0.0V
J 0
(-4195 3832);
DISPLAY 0.340426 (-4195 3832);
PAINT SKYBLUE (-4195 3832);
DISPLAY INVISIBLE (-4195 3832);
FORCEPROP 1 LAST SIZE 1B
J 0
(-4075 3825);
DISPLAY 0.872340 (-4075 3825);
PAINT AQUA (-4075 3825);
DISPLAY INVISIBLE (-4075 3825);
FORCEPROP 1 LAST PATH I98
J 0
(-4075 3875);
DISPLAY 0.872340 (-4075 3875);
PAINT AQUA (-4075 3875);
DISPLAY INVISIBLE (-4075 3875);
FORCEPROP 2 LAST CDS_LIB mstr_symbols
J 0
(-4150 3875);
PAINT MONO (-4150 3875);
DISPLAY INVISIBLE (-4150 3875);
FORCEPROP 1 LAST BODY_TYPE PLUMBING
J 0
(-4195 3832);
DISPLAY 0.340426 (-4195 3832);
PAINT GREEN (-4195 3832);
DISPLAY INVISIBLE (-4195 3832);
FORCEPROP 1 LAST HDL_POWER GND
J 0
(-4150 4025);
DISPLAY 0.872340 (-4150 4025);
PAINT GREEN (-4150 4025);
DISPLAY INVISIBLE (-4150 4025);
FORCEADD RES..2
(-5875 3075);
FORCEPROP 1 LAST LOCATION R1L19
J 0
(-5830 3200);
DISPLAY 0.617021 (-5830 3200);
PAINT AQUA (-5830 3200);
FORCEPROP 1 LAST VALUE 4.75K
J 0
(-5830 3150);
DISPLAY 0.617021 (-5830 3150);
PAINT SKYBLUE (-5830 3150);
FORCEPROP 1 LAST TOLERANCE 1%
J 0
(-5830 3100);
DISPLAY 0.617021 (-5830 3100);
PAINT SKYBLUE (-5830 3100);
FORCEPROP 1 LASTPIN (-5875 3175) $PN 1
J 0
(-5870 3137);
DISPLAY 0.787234 (-5870 3137);
PAINT ORANGE (-5870 3137);
FORCEPROP 1 LASTPIN (-5875 2975) $PN 2
J 0
(-5870 2985);
DISPLAY 0.787234 (-5870 2985);
PAINT ORANGE (-5870 2985);
FORCEPROP 1 LAST WATTAGE 1/16W
J 0
(-5835 3050);
DISPLAY 0.617021 (-5835 3050);
PAINT SKYBLUE (-5835 3050);
FORCEPROP 1 LAST MATERIAL CHIP
J 0
(-5835 3000);
DISPLAY 0.617021 (-5835 3000);
PAINT SKYBLUE (-5835 3000);
FORCEPROP 1 LAST PART_NUMBER G21796-072
J 0
(-5835 2950);
DISPLAY 0.617021 (-5835 2950);
PAINT BLUE (-5835 2950);
FORCEPROP 1 LAST PACK_TYPE 0402
J 0
(-5835 2900);
DISPLAY 0.617021 (-5835 2900);
PAINT SKYBLUE (-5835 2900);
FORCEPROP 2 LAST CDS_LIB mstr_discrete
J 0
(-5875 3075);
PAINT MONO (-5875 3075);
DISPLAY INVISIBLE (-5875 3075);
FORCEPROP 1 LAST PATH I99
J 0
(-5825 3250);
DISPLAY 0.978723 (-5825 3250);
PAINT WHITE (-5825 3250);
DISPLAY INVISIBLE (-5825 3250);
FORCEPROP 0 LAST ROOM M-SATA
J 0
(-5825 3300);
DISPLAY 1.021277 (-5825 3300);
PAINT ORANGE (-5825 3300);
DISPLAY INVISIBLE (-5825 3300);
FORCEPROP 0 LAST BOM_COST M-SATA
J 0
(-5825 3400);
DISPLAY 1.021277 (-5825 3400);
PAINT ORANGE (-5825 3400);
DISPLAY INVISIBLE (-5825 3400);
FORCEPROP 2 LAST SEC 1
J 0
(-5825 3300);
DISPLAY 0.680851 (-5825 3300);
PAINT MONO (-5825 3300);
DISPLAY INVISIBLE (-5825 3300);
FORCEPROP 2 LAST SEC_TYPE 0402
J 0
(-5825 3300);
DISPLAY 1.021277 (-5825 3300);
PAINT ORANGE (-5825 3300);
DISPLAY INVISIBLE (-5825 3300);
FORCEADD CAD_NOTE..1
(-3525 2250);
FORCEPROP 0 LAST L1 PLACE 0.1UF CAP CLOSE TO VCC OF 74AHCT1G86
J 0
(-3675 2125);
DISPLAY 1.021277 (-3675 2125);
PAINT ORANGE (-3675 2125);
FORCEPROP 2 LAST CDS_LIB mstr_symbols
J 0
(-3525 2250);
PAINT MONO (-3525 2250);
DISPLAY INVISIBLE (-3525 2250);
FORCEPROP 1 LAST COMMENT_BODY TRUE
J 0
(-3500 2350);
DISPLAY 0.978723 (-3500 2350);
PAINT ORANGE (-3500 2350);
DISPLAY INVISIBLE (-3500 2350);
FORCEADD CAD_NOTE..1
(-5700 2100);
FORCEPROP 0 LAST L4 ON BOARD EDGE
J 0
(-5850 1800);
DISPLAY 1.021277 (-5850 1800);
PAINT ORANGE (-5850 1800);
FORCEPROP 0 LAST L3 YELLOW LED SHOULD BE LEFT-MOST LED
J 0
(-5850 1850);
DISPLAY 1.021277 (-5850 1850);
PAINT ORANGE (-5850 1850);
FORCEPROP 0 LAST L2 DEBUG HEADER AND BOARD EDGE
J 0
(-5850 1900);
DISPLAY 1.021277 (-5850 1900);
PAINT ORANGE (-5850 1900);
FORCEPROP 0 LAST L1 PLACE YELLOW LED IN BETWEEN BMC
J 0
(-5850 1950);
DISPLAY 1.021277 (-5850 1950);
PAINT ORANGE (-5850 1950);
FORCEPROP 2 LAST CDS_LIB mstr_symbols
J 0
(-5700 2100);
PAINT MONO (-5700 2100);
DISPLAY INVISIBLE (-5700 2100);
FORCEPROP 1 LAST COMMENT_BODY TRUE
J 0
(-5675 2200);
DISPLAY 0.978723 (-5675 2200);
PAINT ORANGE (-5675 2200);
DISPLAY INVISIBLE (-5675 2200);
FORCEADD CAD_NOTE..1
(-2450 3175);
FORCEPROP 0 LAST L1 PLACE 0.1UF CAP NEXT TO VCC PIN ON 74LVC2G14
J 0
(-2600 3025);
DISPLAY 1.021277 (-2600 3025);
PAINT ORANGE (-2600 3025);
FORCEPROP 2 LAST CDS_LIB mstr_symbols
J 0
(-2450 3175);
PAINT MONO (-2450 3175);
DISPLAY INVISIBLE (-2450 3175);
FORCEPROP 1 LAST COMMENT_BODY TRUE
J 0
(-2425 3275);
DISPLAY 0.978723 (-2425 3275);
PAINT ORANGE (-2425 3275);
DISPLAY INVISIBLE (-2425 3275);
FORCEADD CAD_NOTE..1
(-2450 4650);
FORCEPROP 0 LAST L1 PLACE 0.1UF CAP NEXT TO VCC PIN ON 74LVC2G14
J 0
(-2600 4500);
DISPLAY 1.021277 (-2600 4500);
PAINT ORANGE (-2600 4500);
FORCEPROP 2 LAST CDS_LIB mstr_symbols
J 0
(-2450 4650);
PAINT ORANGE (-2450 4650);
DISPLAY INVISIBLE (-2450 4650);
FORCEPROP 1 LAST COMMENT_BODY TRUE
J 0
(-2425 4750);
DISPLAY 0.978723 (-2425 4750);
PAINT ORANGE (-2425 4750);
DISPLAY INVISIBLE (-2425 4750);
FORCEADD CAD_NOTE..1
(-975 3650);
FORCEPROP 0 LAST L2 ON TTL1G07_A
J 2
(-725 3450);
DISPLAY 1.021277 (-725 3450);
PAINT ORANGE (-725 3450);
FORCEPROP 0 LAST L1 PLACE 0.1UF CAP NEXT TO VCC PIN
J 2
(-725 3525);
DISPLAY 1.021277 (-725 3525);
PAINT ORANGE (-725 3525);
FORCEPROP 2 LAST CDS_LIB mstr_symbols
J 0
(-975 3650);
PAINT ORANGE (-975 3650);
DISPLAY INVISIBLE (-975 3650);
FORCEPROP 1 LAST COMMENT_BODY TRUE
J 0
(-950 3750);
DISPLAY 0.978723 (-950 3750);
PAINT ORANGE (-950 3750);
DISPLAY INVISIBLE (-950 3750);
FORCEADD INTEL_CORP_BPAGE..1
(-50 125);
FORCEPROP 1 LAST CDS_CON_LAST_MODIFIED Fri Jun 16 17:49:04 2017
J 0
(-1475 450);
DISPLAY 1.382979 (-1475 450);
PAINT GREEN (-1475 450);
DISPLAY INVISIBLE (-1475 450);
FORCEPROP 1 LAST CUSTOM_TXT_CDS <CURRENT_DESIGN_SHEET> OF <TOTAL_DESIGN_SHEETS>
J 0
(-550 150);
PAINT ORANGE (-550 150);
FORCEPROP 2 LAST CUSTOM_TXT_CDS <XR_PAGE_TITLE>
J 0
(-7940 5375);
DISPLAY 0.638298 (-7940 5375);
PAINT PINK (-7940 5375);
DISPLAY INVISIBLE (-7940 5375);
FORCEPROP 2 LAST CUSTOM_TXT_CDS <CON_LAST_MODIFIED>
J 0
(-4050 200);
DISPLAY 1.382979 (-4050 200);
PAINT ORANGE (-4050 200);
FORCEPROP 1 LAST SCH_TITLE PWR, RESET BTN & LEDS
J 0
(-8000 175);
DISPLAY 1.212766 (-8000 175);
PAINT ORANGE (-8000 175);
FORCEPROP 2 LAST PAGE_BORDER TRUE
J 0
(-7940 5375);
DISPLAY 0.872340 (-7940 5375);
PAINT PINK (-7940 5375);
DISPLAY INVISIBLE (-7940 5375);
FORCEPROP 2 LAST CDS_LIB mstr_symbols
J 0
(-50 125);
DISPLAY 1.382979 (-50 125);
PAINT ORANGE (-50 125);
DISPLAY INVISIBLE (-50 125);
FORCEPROP 1 LAST COMMENT_BODY TRUE
J 0
(-38 137);
DISPLAY 0.617021 (-38 137);
PAINT PEACH (-38 137);
DISPLAY INVISIBLE (-38 137);
FORCEPROP 2 LAST CDS_XR_PAGE_TITLE CR-175 : @BASEBOARD_FAB2_LIB.BASEBOARD_FAB2(SCH_1):PAGE175
J 0
(-7940 5375);
DISPLAY 0.638298 (-7940 5375);
PAINT PINK (-7940 5375);
DISPLAY INVISIBLE (-7940 5375);
WIRE 16 -1 (-4975 3725)(-4975 3850);
WIRE 16 -1 (-4925 2325)(-4925 2450);
WIRE 16 -1 (-5875 3350)(-5875 3175);
WIRE 16 -1 (-7625 2300)(-7625 2575);
WIRE 16 -1 (-7625 2775)(-7625 2575);
WIRE 16 -1 (-7625 2575)(-7225 2575);
WIRE 16 -1 (-7625 2775)(-7225 2775);
WIRE 16 -1 (-7675 3700)(-7675 3775);
WIRE 16 -1 (-6750 3775)(-7675 3775);
WIRE 16 -1 (-7675 3775)(-7675 4050);
WIRE 16 -1 (-7675 4050)(-7300 4050);
WIRE 16 -1 (-6750 4050)(-6750 3775);
WIRE 16 -1 (-7100 4050)(-6750 4050);
WIRE 16 -1 (-2975 2850)(-2975 2900);
WIRE 16 -1 (-2950 4350)(-2950 4250);
WIRE 16 -1 (-2950 4650)(-2950 4600);
WIRE 16 -1 (-3100 4600)(-2950 4600);
WIRE 16 -1 (-2950 4600)(-2950 4550);
WIRE 16 -1 (-3100 4125)(-3100 4600);
WIRE 16 -1 (-3325 4125)(-3100 4125);
WIRE 16 -1 (-2975 3150)(-2975 3200);
WIRE 16 -1 (-3150 3150)(-2975 3150);
WIRE 16 -1 (-2975 3150)(-2975 3100);
WIRE 16 -1 (-3150 2725)(-3150 3150);
WIRE 16 -1 (-3375 2725)(-3150 2725);
WIRE 16 -1 (-5025 800)(-5025 975);
WIRE 16 -1 (-1175 1650)(-1175 1450);
WIRE 16 -1 (-5925 4750)(-5925 4575);
WIRE 16 -1 (-2900 1625)(-2900 1525);
WIRE 16 -1 (-575 3750)(-575 3600);
WIRE 16 -1 (-575 3250)(-575 3400);
WIRE 16 -1 (-3700 1775)(-3700 1550);
WIRE 16 -1 (-3900 1550)(-3700 1550);
WIRE 16 -1 (-2900 1925)(-2900 1825);
WIRE 16 -1 (-4200 2725)(-4200 2525);
WIRE 16 -1 (-4075 2725)(-4200 2725);
WIRE 16 -1 (-4150 4125)(-4150 3925);
WIRE 16 -1 (-4025 4125)(-4150 4125);
WIRE 3 2175 (-6850 4400)(-6850 3900);
WIRE 3 2175 (-7600 3900)(-6850 3900);
WIRE 3 2175 (-7600 4400)(-6850 4400);
WIRE 3 2175 (-7600 4400)(-7600 3900);
WIRE 3 2175 (-4275 2325)(-925 2325);
WIRE 3 2175 (-925 3375)(-925 2325);
WIRE 3 2175 (-4275 3375)(-4275 2325);
WIRE 3 2175 (-4275 3375)(-925 3375);
WIRE 16 -1 (-7275 3525)(-5925 3525);
WIRE 16 -1 (-5925 3525)(-5925 4175);
WIRE 16 -1 (-5925 4375)(-5925 4175);
WIRE 16 -1 (-5925 4175)(-5750 4175);
WIRE 16 -1 (-6750 4175)(-5925 4175);
WIRE 16 -1 (-7100 4300)(-6750 4300);
WIRE 16 -1 (-6750 4300)(-6750 4175);
FORCEPROP 2 LAST SIG_NAME FP_PWR_BTN_R_N
J 0
(-7285 3535);
DISPLAY 0.617021 (-7285 3535);
PAINT ORANGE (-7285 3535);
WIRE 16 -1 (-6750 4500)(-6750 4300);
WIRE 16 -1 (-7700 4500)(-6750 4500);
WIRE 16 -1 (-7700 4300)(-7700 4500);
WIRE 16 -1 (-7300 4300)(-7700 4300);
WIRE 3 2175 (-8000 3400)(-6625 3400);
WIRE 3 2175 (-6625 3600)(-6625 3400);
WIRE 3 2175 (-8000 3600)(-8000 3400);
WIRE 3 2175 (-8000 3600)(-6625 3600);
WIRE 3 2175 (-4600 4825)(-900 4825);
WIRE 3 2175 (-900 4825)(-900 3775);
WIRE 3 2175 (-4600 4825)(-4600 3775);
WIRE 3 2175 (-4600 3775)(-900 3775);
WIRE 16 -1 (-2450 1025)(-1800 1025);
FORCEPROP 2 LAST SIG_NAME FP_ID_LED_P5V_STBY_N
J 0
(-2360 1035);
DISPLAY 0.617021 (-2360 1035);
PAINT ORANGE (-2360 1035);
FORCEPROP 2 LASTPROP $XRERR UNIQUE?
J 0
(-2600 1035);
DISPLAY 0.638298 (-2600 1035);
PAINT MONO (-2600 1035);
DISPLAY INVISIBLE (-2600 1035);
WIRE 16 -1 (-5875 2775)(-5700 2775);
WIRE 16 -1 (-5875 2975)(-5875 2775);
WIRE 16 -1 (-6975 2775)(-6100 2775);
WIRE 16 -1 (-6100 2775)(-5875 2775);
WIRE 16 -1 (-6975 2475)(-6975 2575);
WIRE 16 -1 (-6975 2475)(-6100 2475);
WIRE 16 -1 (-6100 2475)(-6100 2775);
WIRE 16 -1 (-6100 1925)(-6100 2475);
WIRE 16 -1 (-7500 1925)(-6100 1925);
FORCEPROP 2 LAST SIG_NAME FM_DEBUG_RST_BTN_N
J 0
(-7385 1935);
DISPLAY 0.617021 (-7385 1935);
PAINT ORANGE (-7385 1935);
WIRE 16 -1 (-5025 1375)(-5025 1550);
FORCEPROP 2 LAST SIG_NAME FM_SPEAKER_PCH_N
J 0
(-5235 1560);
DISPLAY 0.617021 (-5235 1560);
PAINT ORANGE (-5235 1560);
FORCEPROP 2 LASTPROP $XRERR UNIQUE?
J 0
(-5475 1560);
DISPLAY 0.638298 (-5475 1560);
PAINT MONO (-5475 1560);
DISPLAY INVISIBLE (-5475 1560);
WIRE 16 -1 (-5025 1550)(-4700 1550);
WIRE 16 -1 (-4100 1550)(-4500 1550);
FORCEPROP 2 LAST SIG_NAME FM_BEEP_LED_P
J 0
(-4410 1560);
DISPLAY 0.617021 (-4410 1560);
PAINT ORANGE (-4410 1560);
FORCEPROP 2 LASTPROP $XRERR UNIQUE?
J 0
(-4650 1560);
DISPLAY 0.638298 (-4650 1560);
PAINT MONO (-4650 1560);
DISPLAY INVISIBLE (-4650 1560);
WIRE 3 273 (-5650 3300)(-5650 2850);
WIRE 3 273 (-6000 3300)(-5650 3300);
WIRE 3 273 (-6000 2850)(-5650 2850);
WIRE 3 273 (-6000 2850)(-6000 3300);
WIRE 16 -1 (-4925 2650)(-4925 2775);
WIRE 16 -1 (-4925 2775)(-4075 2775);
WIRE 16 -1 (-5500 2775)(-4925 2775);
FORCEPROP 2 LAST SIG_NAME FP_RST_BTN_R_N
J 0
(-5435 2785);
DISPLAY 0.617021 (-5435 2785);
PAINT ORANGE (-5435 2785);
FORCEPROP 2 LASTPROP $XRERR UNIQUE?
J 0
(-5675 2785);
DISPLAY 0.638298 (-5675 2785);
PAINT MONO (-5675 2785);
DISPLAY INVISIBLE (-5675 2785);
WIRE 16 -1 (-2125 2675)(-1500 2675);
FORCEPROP 2 LAST SIG_NAME RST_SYSTEM_BTN_N
J 0
(-2060 2685);
DISPLAY 0.617021 (-2060 2685);
PAINT ORANGE (-2060 2685);
WIRE 16 -1 (-5550 4175)(-4975 4175);
FORCEPROP 2 LAST SIG_NAME FP_PWR_BTN_R1_N
J 0
(-5485 4185);
DISPLAY 0.617021 (-5485 4185);
PAINT ORANGE (-5485 4185);
FORCEPROP 2 LASTPROP $XRERR UNIQUE?
J 0
(-5725 4185);
DISPLAY 0.638298 (-5725 4185);
PAINT MONO (-5725 4185);
DISPLAY INVISIBLE (-5725 4185);
WIRE 16 -1 (-4975 4175)(-4025 4175);
WIRE 16 -1 (-4975 4050)(-4975 4175);
WIRE 16 -1 (-2175 4075)(-1400 4075);
FORCEPROP 2 LAST SIG_NAME FM_PWR_BTN_N
J 0
(-2010 4085);
DISPLAY 0.617021 (-2010 4085);
PAINT ORANGE (-2010 4085);
WIRE 16 -1 (-4025 1075)(-3625 1075);
FORCEPROP 2 LAST SIG_NAME PWRGD_P3V3
J 0
(-3960 1085);
DISPLAY 0.617021 (-3960 1085);
PAINT ORANGE (-3960 1085);
WIRE 16 -1 (-5850 1075)(-5225 1075);
FORCEPROP 2 LAST SIG_NAME FM_BIOS_TOP_SWAP_SPKR
J 0
(-5835 1085);
DISPLAY 0.617021 (-5835 1085);
PAINT ORANGE (-5835 1085);
WIRE 16 -1 (-4025 975)(-2950 975);
FORCEPROP 2 LAST SIG_NAME FP_PWR_ID_LED_N
J 0
(-3960 985);
DISPLAY 0.617021 (-3960 985);
PAINT ORANGE (-3960 985);
WIRE 16 -1 (-3425 1075)(-2950 1075);
FORCEPROP 2 LAST SIG_NAME PWRGD_P3V3_R
J 0
(-3360 1085);
DISPLAY 0.617021 (-3360 1085);
PAINT ORANGE (-3360 1085);
FORCEPROP 2 LASTPROP $XRERR UNIQUE?
J 0
(-3600 1085);
DISPLAY 0.638298 (-3600 1085);
PAINT MONO (-3600 1085);
DISPLAY INVISIBLE (-3600 1085);
WIRE 16 -1 (-3375 2675)(-3000 2675);
FORCEPROP 2 LAST SIG_NAME RST_SYSTEM_BTN_BUF_N
J 0
(-3085 2700);
DISPLAY 0.617021 (-3085 2700);
PAINT ORANGE (-3085 2700);
WIRE 16 -1 (-3000 2675)(-2325 2675);
WIRE 16 -1 (-3000 2675)(-3000 2450);
WIRE 16 -1 (-3000 2450)(-2325 2450);
WIRE 16 -1 (-3175 4175)(-3325 4175);
WIRE 16 -1 (-3175 3825)(-3175 4175);
WIRE 16 -1 (-4025 3825)(-3175 3825);
FORCEPROP 2 LAST SIG_NAME FP_PWR_BTN_BUF1_N
J 0
(-3885 3860);
DISPLAY 0.617021 (-3885 3860);
PAINT ORANGE (-3885 3860);
FORCEPROP 2 LASTPROP $XRERR UNIQUE?
J 0
(-4125 3860);
DISPLAY 0.638298 (-4125 3860);
PAINT MONO (-4125 3860);
DISPLAY INVISIBLE (-4125 3860);
WIRE 16 -1 (-4025 4075)(-4025 3825);
WIRE 16 -1 (-3325 4075)(-2375 4075);
FORCEPROP 2 LAST SIG_NAME FM_PWR_BTN_R_N
J 0
(-3010 4085);
DISPLAY 0.617021 (-3010 4085);
PAINT ORANGE (-3010 4085);
FORCEPROP 2 LASTPROP $XRERR UNIQUE?
J 0
(-3250 4085);
DISPLAY 0.638298 (-3250 4085);
PAINT MONO (-3250 4085);
DISPLAY INVISIBLE (-3250 4085);
WIRE 16 -1 (-3225 2775)(-3375 2775);
WIRE 16 -1 (-3225 2450)(-3225 2775);
WIRE 16 -1 (-4075 2675)(-4075 2450);
WIRE 16 -1 (-4075 2450)(-3225 2450);
FORCEPROP 2 LAST SIG_NAME FP_RST_BTN_BUF1_N
J 0
(-3885 2460);
DISPLAY 0.617021 (-3885 2460);
PAINT ORANGE (-3885 2460);
FORCEPROP 2 LASTPROP $XRERR UNIQUE?
J 0
(-4125 2460);
DISPLAY 0.638298 (-4125 2460);
PAINT MONO (-4125 2460);
DISPLAY INVISIBLE (-4125 2460);
WIRE 16 -1 (-1175 1025)(-1600 1025);
FORCEPROP 2 LAST SIG_NAME FP_ID_LED_XOR_R
J 0
(-1535 1035);
DISPLAY 0.617021 (-1535 1035);
PAINT ORANGE (-1535 1035);
FORCEPROP 2 LASTPROP $XRERR UNIQUE?
J 0
(-1775 1035);
DISPLAY 0.638298 (-1775 1035);
PAINT MONO (-1775 1035);
DISPLAY INVISIBLE (-1775 1035);
WIRE 16 -1 (-1175 1250)(-1175 1025);
DOT 1 (-5875 2775);
DOT 1 (-4975 4175);
DOT 1 (-2950 4600);
DOT 1 (-2975 3150);
DOT 1 (-6750 4300);
DOT 1 (-7625 2575);
DOT 1 (-6100 2475);
DOT 1 (-5925 4175);
DOT 1 (-4925 2775);
DOT 1 (-6100 2775);
DOT 1 (-7675 3775);
DOT 1 (-3000 2675);
FORCENOTE
ID LED LIGHT WHEN NORMAL POWER IS UP.
(-2450 725) 0;
DISPLAY LEFT (-2450 725);
DISPLAY 1.021277 (-2450 725);
PAINT PURPLE (-2450 725);
FORCENOTE
PIN1 PIN2 | PIN4
(-2450 1375) 0;
DISPLAY LEFT (-2450 1375);
DISPLAY 1.021277 (-2450 1375);
PAINT PURPLE (-2450 1375);
FORCENOTE
1  0 | 1
(-2375 1225) 0;
DISPLAY LEFT (-2375 1225);
DISPLAY 1.021277 (-2375 1225);
PAINT PURPLE (-2375 1225);
FORCENOTE
U1L2 TRUTH TABLE
(-2475 1425) 0;
DISPLAY LEFT (-2475 1425);
DISPLAY 1.021277 (-2475 1425);
PAINT PURPLE (-2475 1425);
FORCENOTE
0  0 | 0
(-2375 1325) 0;
DISPLAY LEFT (-2375 1325);
DISPLAY 1.021277 (-2375 1325);
PAINT PURPLE (-2375 1325);
FORCENOTE
1  1 | 0
(-2375 1175) 0;
DISPLAY LEFT (-2375 1175);
DISPLAY 1.021277 (-2375 1175);
PAINT PURPLE (-2375 1175);
FORCENOTE
0  1 | 1
(-2375 1275) 0;
DISPLAY LEFT (-2375 1275);
DISPLAY 1.021277 (-2375 1275);
PAINT PURPLE (-2375 1275);
FORCENOTE
IF = 25MA
(-1800 800) 0;
DISPLAY LEFT (-1800 800);
DISPLAY 1.021277 (-1800 800);
PAINT PURPLE (-1800 800);
FORCENOTE
TP FAB1 ADD OFFPAGE 1117
(-7525 3325) 0;
DISPLAY LEFT (-7525 3325);
DISPLAY 1.021277 (-7525 3325);
PAINT RED (-7525 3325);
FORCENOTE
TP FAB1 CHANGE U2R1 PN 1222
(-4600 4850) 0;
DISPLAY LEFT (-4600 4850);
DISPLAY 1.021277 (-4600 4850);
PAINT RED (-4600 4850);
FORCENOTE
IR = 14.9MA
(-3675 1575) 0;
DISPLAY LEFT (-3675 1575);
DISPLAY 1.021277 (-3675 1575);
PAINT PURPLE (-3675 1575);
FORCENOTE
IF = 25MA
(-4700 1325) 0;
DISPLAY LEFT (-4700 1325);
DISPLAY 1.021277 (-4700 1325);
PAINT PURPLE (-4700 1325);
FORCENOTE
IR = 10.6MA
(-1125 1025) 0;
DISPLAY LEFT (-1125 1025);
DISPLAY 1.021277 (-1125 1025);
PAINT PURPLE (-1125 1025);
FORCENOTE
TP FAB1 CHANGE U9A3 PN 1222
(-4625 3425) 0;
DISPLAY LEFT (-4625 3425);
DISPLAY 1.021277 (-4625 3425);
PAINT RED (-4625 3425);
FORCENOTE
TP FAB1  CH ANGE SYMBOL AS S9A1 1207
(-7600 3825) 0;
DISPLAY LEFT (-7600 3825);
DISPLAY 1.021277 (-7600 3825);
PAINT RED (-7600 3825);
FORCENOTE
TP FAB1 CHANGE TO POP FOR CONTROL BOM 0128
(-5850 3350) 0;
DISPLAY LEFT (-5850 3350);
DISPLAY 1.021277 (-5850 3350);
PAINT RED (-5850 3350);
QUIT
